G04 ================== begin FILE IDENTIFICATION RECORD ==================*
G04 Layout Name:  17301-sa.brd*
G04 Film Name:    DRILL*
G04 File Format:  Gerber RS274X*
G04 File Origin:  Cadence Allegro 16.6-2015-S079*
G04 Origin Date:  Thu Jun 22 17:49:51 2017*
G04 *
G04 Layer:  MANUFACTURING/NCLEGEND-1-6*
G04 Layer:  MANUFACTURING/DRILL SIZE*
G04 Layer:  DRAWING FORMAT/LAYER_PCB_STORY*
G04 Layer:  DRAWING FORMAT/LAYER_DRILL*
G04 Layer:  BOARD GEOMETRY/PANEL_OUTLINE*
G04 *
G04 Offset:    (0.00 0.00)*
G04 Mirror:    No*
G04 Mode:      Positive*
G04 Rotation:  0*
G04 FullContactRelief:  No*
G04 UndefLineWidth:     6.00*
G04 ================== end FILE IDENTIFICATION RECORD ====================*
%FSLAX35Y35*MOIN*%
%IR0*IPPOS*OFA0.00000B0.00000*MIA0B0*SFA1.00000B1.00000*%
%AMMACRO17*
1,1,.006,.00787,0.0*
20,1,.006,.00787,0.0,.003935,.006816,0.0*
1,1,.006,.003935,.006816*
20,1,.006,.003935,.006816,-.003935,.006816,0.0*
1,1,.006,-.003935,.006816*
20,1,.006,-.003935,.006816,-.00787,0.0,0.0*
1,1,.006,-.00787,0.0*
20,1,.006,-.00787,0.0,-.003935,-.006816,0.0*
1,1,.006,-.003935,-.006816*
20,1,.006,-.003935,-.006816,.003935,-.006816,0.0*
1,1,.006,.003935,-.006816*
20,1,.006,.003935,-.006816,.00787,0.0,0.0*
1,1,.006,.00787,0.0*
1,1,.006,-.00288,-.00236*
20,1,.006,-.00288,-.00236,-.00209,-.00327,0.0*
1,1,.006,-.00209,-.00327*
20,1,.006,-.00209,-.00327,-.00104,-.0038,0.0*
1,1,.006,-.00104,-.0038*
20,1,.006,-.00104,-.0038,.00014,-.00393,0.0*
1,1,.006,.00014,-.00393*
20,1,.006,.00014,-.00393,.00119,-.0038,0.0*
1,1,.006,.00119,-.0038*
20,1,.006,.00119,-.0038,.00223,-.00314,0.0*
1,1,.006,.00223,-.00314*
20,1,.006,.00223,-.00314,.00289,-.00236,0.0*
1,1,.006,.00289,-.00236*
20,1,.006,.00289,-.00236,.00302,-.00157,0.0*
1,1,.006,.00302,-.00157*
20,1,.006,.00302,-.00157,.00276,-.00065,0.0*
1,1,.006,.00276,-.00065*
20,1,.006,.00276,-.00065,.00184,0.0,0.0*
1,1,.006,.00184,0.0*
20,1,.006,.00184,0.0,.00092,.00027,0.0*
1,1,.006,.00092,.00027*
20,1,.006,.00092,.00027,-.00026,.00027,0.0*
1,1,.006,-.00026,.00027*
1,1,.006,.00092,.00027*
20,1,.006,.00092,.00027,.00171,.00066,0.0*
1,1,.006,.00171,.00066*
20,1,.006,.00171,.00066,.00237,.00132,0.0*
1,1,.006,.00237,.00132*
20,1,.006,.00237,.00132,.00263,.0021,0.0*
1,1,.006,.00263,.0021*
20,1,.006,.00263,.0021,.00237,.00289,0.0*
1,1,.006,.00237,.00289*
20,1,.006,.00237,.00289,.00171,.00355,0.0*
1,1,.006,.00171,.00355*
20,1,.006,.00171,.00355,.00053,.00394,0.0*
1,1,.006,.00053,.00394*
20,1,.006,.00053,.00394,-.00065,.00381,0.0*
1,1,.006,-.00065,.00381*
20,1,.006,-.00065,.00381,-.00183,.00328,0.0*
1,1,.006,-.00183,.00328*
%
%ADD17MACRO17*%
%AMMACRO16*
1,1,.006,0.0,.00984*
20,1,.006,0.0,.00984,-.008522,.00492,0.0*
1,1,.006,-.008522,.00492*
20,1,.006,-.008522,.00492,-.008522,-.00492,0.0*
1,1,.006,-.008522,-.00492*
20,1,.006,-.008522,-.00492,0.0,-.00984,0.0*
1,1,.006,0.0,-.00984*
20,1,.006,0.0,-.00984,.008522,-.00492,0.0*
1,1,.006,.008522,-.00492*
20,1,.006,.008522,-.00492,.008522,.00492,0.0*
1,1,.006,.008522,.00492*
20,1,.006,.008522,.00492,0.0,.00984,0.0*
1,1,.006,0.0,.00984*
1,1,.006,.00197,-.00492*
20,1,.006,.00197,-.00492,.00197,.00492,0.0*
1,1,.006,.00197,.00492*
20,1,.006,.00197,.00492,-.0041,-.00213,0.0*
1,1,.006,-.0041,-.00213*
20,1,.006,-.0041,-.00213,.0041,-.00213,0.0*
1,1,.006,.0041,-.00213*
%
%ADD16MACRO16*%
%AMMACRO15*
1,1,.006,.005,0.0*
20,1,.006,.005,0.0,-.005,0.0,0.0*
1,1,.006,-.005,0.0*
1,1,.006,0.0,.005*
20,1,.006,0.0,.005,0.0,-.005,0.0*
1,1,.006,0.0,-.005*
1,1,.006,.0025,0.0*
20,1,.006,.0025,0.0,.0025,.005,0.0*
1,1,.006,.0025,.005*
20,1,.006,.0025,.005,.0015,.004,0.0*
1,1,.006,.0015,.004*
1,1,.006,.0015,0.0*
20,1,.006,.0015,0.0,.0035,0.0,0.0*
1,1,.006,.0035,0.0*
%
%ADD15MACRO15*%
%AMMACRO13*
1,1,.006,.006,.006*
20,1,.006,.006,.006,.006,-.006,0.0*
1,1,.006,.006,-.006*
20,1,.006,.006,-.006,-.006,-.006,0.0*
1,1,.006,-.006,-.006*
20,1,.006,-.006,-.006,-.006,.006,0.0*
1,1,.006,-.006,.006*
20,1,.006,-.006,.006,.006,.006,0.0*
1,1,.006,.006,.006*
1,1,.006,-.0019,.002*
20,1,.006,-.0019,.002,-.0013,.0026,0.0*
1,1,.006,-.0013,.0026*
20,1,.006,-.0013,.0026,-.0006,.0029,0.0*
1,1,.006,-.0006,.0029*
20,1,.006,-.0006,.0029,.0002,.003,0.0*
1,1,.006,.0002,.003*
20,1,.006,.0002,.003,.0012,.0028,0.0*
1,1,.006,.0012,.0028*
20,1,.006,.0012,.0028,.0019,.0023,0.0*
1,1,.006,.0019,.0023*
20,1,.006,.0019,.0023,.0021,.0017,0.0*
1,1,.006,.0021,.0017*
20,1,.006,.0021,.0017,.002,.0011,0.0*
1,1,.006,.002,.0011*
20,1,.006,.002,.0011,.0016,.0006,0.0*
1,1,.006,.0016,.0006*
20,1,.006,.0016,.0006,-.0004,-.0004,0.0*
1,1,.006,-.0004,-.0004*
20,1,.006,-.0004,-.0004,-.0013,-.0011,0.0*
1,1,.006,-.0013,-.0011*
20,1,.006,-.0013,-.0011,-.0019,-.0021,0.0*
1,1,.006,-.0019,-.0021*
20,1,.006,-.0019,-.0021,-.0021,-.003,0.0*
1,1,.006,-.0021,-.003*
20,1,.006,-.0021,-.003,.0021,-.003,0.0*
1,1,.006,.0021,-.003*
%
%ADD13MACRO13*%
%AMMACRO22*
1,1,.006,.009527,-.023*
20,1,.006,.009527,-.023,-.009527,-.023,0.0*
1,1,.006,-.009527,-.023*
20,1,.006,-.009527,-.023,-.023,-.009527,0.0*
1,1,.006,-.023,-.009527*
20,1,.006,-.023,-.009527,-.023,.009527,0.0*
1,1,.006,-.023,.009527*
20,1,.006,-.023,.009527,-.009527,.023,0.0*
1,1,.006,-.009527,.023*
20,1,.006,-.009527,.023,.009527,.023,0.0*
1,1,.006,.009527,.023*
20,1,.006,.009527,.023,.023,.009527,0.0*
1,1,.006,.023,.009527*
20,1,.006,.023,.009527,.023,-.009527,0.0*
1,1,.006,.023,-.009527*
20,1,.006,.023,-.009527,.009527,-.023,0.0*
1,1,.006,.009527,-.023*
1,1,.006,-.00843,-.00805*
20,1,.006,-.00843,-.00805,-.00613,-.00997,0.0*
1,1,.006,-.00613,-.00997*
20,1,.006,-.00613,-.00997,-.00345,-.01112,0.0*
1,1,.006,-.00345,-.01112*
20,1,.006,-.00345,-.01112,0.0,-.0115,0.0*
1,1,.006,0.0,-.0115*
20,1,.006,0.0,-.0115,.00345,-.01073,0.0*
1,1,.006,.00345,-.01073*
20,1,.006,.00345,-.01073,.00613,-.0092,0.0*
1,1,.006,.00613,-.0092*
20,1,.006,.00613,-.0092,.00805,-.00652,0.0*
1,1,.006,.00805,-.00652*
20,1,.006,.00805,-.00652,.00843,-.00345,0.0*
1,1,.006,.00843,-.00345*
20,1,.006,.00843,-.00345,.00767,-.00038,0.0*
1,1,.006,.00767,-.00038*
20,1,.006,.00767,-.00038,.00575,.00153,0.0*
1,1,.006,.00575,.00153*
20,1,.006,.00575,.00153,.00307,.00307,0.0*
1,1,.006,.00307,.00307*
20,1,.006,.00307,.00307,.00038,.00345,0.0*
1,1,.006,.00038,.00345*
20,1,.006,.00038,.00345,-.0023,.00307,0.0*
1,1,.006,-.0023,.00307*
20,1,.006,-.0023,.00307,-.00575,.00153,0.0*
1,1,.006,-.00575,.00153*
20,1,.006,-.00575,.00153,-.0046,.0115,0.0*
1,1,.006,-.0046,.0115*
20,1,.006,-.0046,.0115,.00575,.0115,0.0*
1,1,.006,.00575,.0115*
%
%ADD22MACRO22*%
%AMMACRO10*
1,1,.006,-.03583,-.043*
20,1,.006,-.03583,-.043,0.0,.043,0.0*
1,1,.006,0.0,.043*
20,1,.006,0.0,.043,.03583,-.043,0.0*
1,1,.006,.03583,-.043*
1,1,.006,.02293,-.0129*
20,1,.006,.02293,-.0129,-.02293,-.0129,0.0*
1,1,.006,-.02293,-.0129*
%
%ADD10MACRO10*%
%AMMACRO19*
1,1,.006,-.019,.01*
20,1,.006,-.019,.01,.019,.01,0.0*
1,1,.006,.019,.01*
20,1,.006,.019,.01,.020736,.009848,0.0*
1,1,.006,.020736,.009848*
20,1,.006,.020736,.009848,.02242,.009397,0.0*
1,1,.006,.02242,.009397*
20,1,.006,.02242,.009397,.024,.00866,0.0*
1,1,.006,.024,.00866*
20,1,.006,.024,.00866,.025428,.00766,0.0*
1,1,.006,.025428,.00766*
20,1,.006,.025428,.00766,.02666,.006428,0.0*
1,1,.006,.02666,.006428*
20,1,.006,.02666,.006428,.02766,.005,0.0*
1,1,.006,.02766,.005*
20,1,.006,.02766,.005,.028397,.00342,0.0*
1,1,.006,.028397,.00342*
20,1,.006,.028397,.00342,.028848,.001736,0.0*
1,1,.006,.028848,.001736*
20,1,.006,.028848,.001736,.029,0.0,0.0*
1,1,.006,.029,0.0*
20,1,.006,.029,0.0,.028848,-.001736,0.0*
1,1,.006,.028848,-.001736*
20,1,.006,.028848,-.001736,.028397,-.00342,0.0*
1,1,.006,.028397,-.00342*
20,1,.006,.028397,-.00342,.02766,-.005,0.0*
1,1,.006,.02766,-.005*
20,1,.006,.02766,-.005,.02666,-.006428,0.0*
1,1,.006,.02666,-.006428*
20,1,.006,.02666,-.006428,.025428,-.00766,0.0*
1,1,.006,.025428,-.00766*
20,1,.006,.025428,-.00766,.024,-.00866,0.0*
1,1,.006,.024,-.00866*
20,1,.006,.024,-.00866,.02242,-.009397,0.0*
1,1,.006,.02242,-.009397*
20,1,.006,.02242,-.009397,.020736,-.009848,0.0*
1,1,.006,.020736,-.009848*
20,1,.006,.020736,-.009848,.019,-.01,0.0*
1,1,.006,.019,-.01*
20,1,.006,.019,-.01,-.019,-.01,0.0*
1,1,.006,-.019,-.01*
20,1,.006,-.019,-.01,-.020736,-.009848,0.0*
1,1,.006,-.020736,-.009848*
20,1,.006,-.020736,-.009848,-.02242,-.009397,0.0*
1,1,.006,-.02242,-.009397*
20,1,.006,-.02242,-.009397,-.024,-.00866,0.0*
1,1,.006,-.024,-.00866*
20,1,.006,-.024,-.00866,-.025428,-.00766,0.0*
1,1,.006,-.025428,-.00766*
20,1,.006,-.025428,-.00766,-.02666,-.006428,0.0*
1,1,.006,-.02666,-.006428*
20,1,.006,-.02666,-.006428,-.02766,-.005,0.0*
1,1,.006,-.02766,-.005*
20,1,.006,-.02766,-.005,-.028397,-.00342,0.0*
1,1,.006,-.028397,-.00342*
20,1,.006,-.028397,-.00342,-.028848,-.001736,0.0*
1,1,.006,-.028848,-.001736*
20,1,.006,-.028848,-.001736,-.029,0.0,0.0*
1,1,.006,-.029,0.0*
20,1,.006,-.029,0.0,-.028848,.001736,0.0*
1,1,.006,-.028848,.001736*
20,1,.006,-.028848,.001736,-.028397,.00342,0.0*
1,1,.006,-.028397,.00342*
20,1,.006,-.028397,.00342,-.02766,.005,0.0*
1,1,.006,-.02766,.005*
20,1,.006,-.02766,.005,-.02666,.006428,0.0*
1,1,.006,-.02666,.006428*
20,1,.006,-.02666,.006428,-.025428,.00766,0.0*
1,1,.006,-.025428,.00766*
20,1,.006,-.025428,.00766,-.024,.00866,0.0*
1,1,.006,-.024,.00866*
20,1,.006,-.024,.00866,-.02242,.009397,0.0*
1,1,.006,-.02242,.009397*
20,1,.006,-.02242,.009397,-.020736,.009848,0.0*
1,1,.006,-.020736,.009848*
20,1,.006,-.020736,.009848,-.019,.01,0.0*
1,1,.006,-.019,.01*
1,1,.006,-.005,-.005*
20,1,.006,-.005,-.005,-.00633,-.00483,0.0*
1,1,.006,-.00633,-.00483*
20,1,.006,-.00633,-.00483,-.0075,-.00417,0.0*
1,1,.006,-.0075,-.00417*
20,1,.006,-.0075,-.00417,-.0085,-.00317,0.0*
1,1,.006,-.0085,-.00317*
20,1,.006,-.0085,-.00317,-.00917,-.002,0.0*
1,1,.006,-.00917,-.002*
20,1,.006,-.00917,-.002,-.0095,-.00067,0.0*
1,1,.006,-.0095,-.00067*
20,1,.006,-.0095,-.00067,-.0095,.00067,0.0*
1,1,.006,-.0095,.00067*
20,1,.006,-.0095,.00067,-.00917,.002,0.0*
1,1,.006,-.00917,.002*
20,1,.006,-.00917,.002,-.0085,.00317,0.0*
1,1,.006,-.0085,.00317*
20,1,.006,-.0085,.00317,-.0075,.00417,0.0*
1,1,.006,-.0075,.00417*
20,1,.006,-.0075,.00417,-.00633,.00483,0.0*
1,1,.006,-.00633,.00483*
20,1,.006,-.00633,.00483,-.005,.005,0.0*
1,1,.006,-.005,.005*
20,1,.006,-.005,.005,-.00367,.00483,0.0*
1,1,.006,-.00367,.00483*
20,1,.006,-.00367,.00483,-.0025,.00417,0.0*
1,1,.006,-.0025,.00417*
20,1,.006,-.0025,.00417,-.0015,.00317,0.0*
1,1,.006,-.0015,.00317*
20,1,.006,-.0015,.00317,-.00083,.002,0.0*
1,1,.006,-.00083,.002*
20,1,.006,-.00083,.002,-.0005,.00067,0.0*
1,1,.006,-.0005,.00067*
20,1,.006,-.0005,.00067,-.0005,-.00067,0.0*
1,1,.006,-.0005,-.00067*
20,1,.006,-.0005,-.00067,-.00083,-.002,0.0*
1,1,.006,-.00083,-.002*
20,1,.006,-.00083,-.002,-.0015,-.00317,0.0*
1,1,.006,-.0015,-.00317*
20,1,.006,-.0015,-.00317,-.0025,-.00417,0.0*
1,1,.006,-.0025,-.00417*
20,1,.006,-.0025,-.00417,-.00367,-.00483,0.0*
1,1,.006,-.00367,-.00483*
20,1,.006,-.00367,-.00483,-.005,-.005,0.0*
1,1,.006,-.005,-.005*
1,1,.006,.00084,-.005*
20,1,.006,.00084,-.005,.00501,.005,0.0*
1,1,.006,.00501,.005*
20,1,.006,.00501,.005,.00918,-.005,0.0*
1,1,.006,.00918,-.005*
1,1,.006,.00768,-.0015*
20,1,.006,.00768,-.0015,.00234,-.0015,0.0*
1,1,.006,.00234,-.0015*
%
%ADD19MACRO19*%
%AMMACRO14*
1,1,.006,.038385,0.0*
20,1,.006,.038385,0.0,0.0,-.038385,0.0*
1,1,.006,0.0,-.038385*
20,1,.006,0.0,-.038385,-.038385,0.0,0.0*
1,1,.006,-.038385,0.0*
20,1,.006,-.038385,0.0,0.0,.038385,0.0*
1,1,.006,0.0,.038385*
20,1,.006,0.0,.038385,.038385,0.0,0.0*
1,1,.006,.038385,0.0*
1,1,.006,-.01215,-.0032*
20,1,.006,-.01215,-.0032,-.00768,.00128,0.0*
1,1,.006,-.00768,.00128*
20,1,.006,-.00768,.00128,-.00384,.00384,0.0*
1,1,.006,-.00384,.00384*
20,1,.006,-.00384,.00384,.00128,.00512,0.0*
1,1,.006,.00128,.00512*
20,1,.006,.00128,.00512,.00576,.00384,0.0*
1,1,.006,.00576,.00384*
20,1,.006,.00576,.00384,.00896,.00128,0.0*
1,1,.006,.00896,.00128*
20,1,.006,.00896,.00128,.01151,-.00256,0.0*
1,1,.006,.01151,-.00256*
20,1,.006,.01151,-.00256,.01215,-.00704,0.0*
1,1,.006,.01215,-.00704*
20,1,.006,.01215,-.00704,.01151,-.01087,0.0*
1,1,.006,.01151,-.01087*
20,1,.006,.01151,-.01087,.00896,-.01471,0.0*
1,1,.006,.00896,-.01471*
20,1,.006,.00896,-.01471,.00512,-.01791,0.0*
1,1,.006,.00512,-.01791*
20,1,.006,.00512,-.01791,.00064,-.01919,0.0*
1,1,.006,.00064,-.01919*
20,1,.006,.00064,-.01919,-.00448,-.01791,0.0*
1,1,.006,-.00448,-.01791*
20,1,.006,-.00448,-.01791,-.00896,-.01407,0.0*
1,1,.006,-.00896,-.01407*
20,1,.006,-.00896,-.01407,-.01151,-.00832,0.0*
1,1,.006,-.01151,-.00832*
20,1,.006,-.01151,-.00832,-.01215,-.00192,0.0*
1,1,.006,-.01215,-.00192*
20,1,.006,-.01215,-.00192,-.01087,.0064,0.0*
1,1,.006,-.01087,.0064*
20,1,.006,-.01087,.0064,-.00896,.01087,0.0*
1,1,.006,-.00896,.01087*
20,1,.006,-.00896,.01087,-.00576,.01535,0.0*
1,1,.006,-.00576,.01535*
20,1,.006,-.00576,.01535,-.00128,.01855,0.0*
1,1,.006,-.00128,.01855*
20,1,.006,-.00128,.01855,.0032,.01919,0.0*
1,1,.006,.0032,.01919*
20,1,.006,.0032,.01919,.00768,.01791,0.0*
1,1,.006,.00768,.01791*
20,1,.006,.00768,.01791,.01087,.01471,0.0*
1,1,.006,.01087,.01471*
%
%ADD14MACRO14*%
%AMMACRO12*
1,1,.006,0.0,.065*
20,1,.006,0.0,.065,.065,-.065,0.0*
1,1,.006,.065,-.065*
20,1,.006,.065,-.065,-.065,-.065,0.0*
1,1,.006,-.065,-.065*
20,1,.006,-.065,-.065,0.0,.065,0.0*
1,1,.006,0.0,.065*
1,1,.006,-.00217,-.0325*
20,1,.006,-.00217,-.0325,0.0,-.01842,0.0*
1,1,.006,0.0,-.01842*
20,1,.006,0.0,-.01842,.00325,-.0065,0.0*
1,1,.006,.00325,-.0065*
20,1,.006,.00325,-.0065,.00758,.00433,0.0*
1,1,.006,.00758,.00433*
20,1,.006,.00758,.00433,.013,.01625,0.0*
1,1,.006,.013,.01625*
20,1,.006,.013,.01625,.02167,.0325,0.0*
1,1,.006,.02167,.0325*
20,1,.006,.02167,.0325,-.02167,.0325,0.0*
1,1,.006,-.02167,.0325*
%
%ADD12MACRO12*%
%AMMACRO18*
1,1,.006,.0265,0.0*
20,1,.006,.0265,0.0,.026097,-.004602,0.0*
1,1,.006,.026097,-.004602*
20,1,.006,.026097,-.004602,.024902,-.009064,0.0*
1,1,.006,.024902,-.009064*
20,1,.006,.024902,-.009064,.02295,-.01325,0.0*
1,1,.006,.02295,-.01325*
20,1,.006,.02295,-.01325,.0203,-.017034,0.0*
1,1,.006,.0203,-.017034*
20,1,.006,.0203,-.017034,.017034,-.0203,0.0*
1,1,.006,.017034,-.0203*
20,1,.006,.017034,-.0203,.01325,-.02295,0.0*
1,1,.006,.01325,-.02295*
20,1,.006,.01325,-.02295,.009064,-.024902,0.0*
1,1,.006,.009064,-.024902*
20,1,.006,.009064,-.024902,.004602,-.026097,0.0*
1,1,.006,.004602,-.026097*
20,1,.006,.004602,-.026097,0.0,-.0265,0.0*
1,1,.006,0.0,-.0265*
20,1,.006,0.0,-.0265,-.004602,-.026097,0.0*
1,1,.006,-.004602,-.026097*
20,1,.006,-.004602,-.026097,-.009064,-.024902,0.0*
1,1,.006,-.009064,-.024902*
20,1,.006,-.009064,-.024902,-.01325,-.02295,0.0*
1,1,.006,-.01325,-.02295*
20,1,.006,-.01325,-.02295,-.017034,-.0203,0.0*
1,1,.006,-.017034,-.0203*
20,1,.006,-.017034,-.0203,-.0203,-.017034,0.0*
1,1,.006,-.0203,-.017034*
20,1,.006,-.0203,-.017034,-.02295,-.01325,0.0*
1,1,.006,-.02295,-.01325*
20,1,.006,-.02295,-.01325,-.024902,-.009064,0.0*
1,1,.006,-.024902,-.009064*
20,1,.006,-.024902,-.009064,-.026097,-.004602,0.0*
1,1,.006,-.026097,-.004602*
20,1,.006,-.026097,-.004602,-.0265,0.0,0.0*
1,1,.006,-.0265,0.0*
20,1,.006,-.0265,0.0,-.026097,.004602,0.0*
1,1,.006,-.026097,.004602*
20,1,.006,-.026097,.004602,-.024902,.009064,0.0*
1,1,.006,-.024902,.009064*
20,1,.006,-.024902,.009064,-.02295,.01325,0.0*
1,1,.006,-.02295,.01325*
20,1,.006,-.02295,.01325,-.0203,.017034,0.0*
1,1,.006,-.0203,.017034*
20,1,.006,-.0203,.017034,-.017034,.0203,0.0*
1,1,.006,-.017034,.0203*
20,1,.006,-.017034,.0203,-.01325,.02295,0.0*
1,1,.006,-.01325,.02295*
20,1,.006,-.01325,.02295,-.009064,.024902,0.0*
1,1,.006,-.009064,.024902*
20,1,.006,-.009064,.024902,-.004602,.026097,0.0*
1,1,.006,-.004602,.026097*
20,1,.006,-.004602,.026097,0.0,.0265,0.0*
1,1,.006,0.0,.0265*
20,1,.006,0.0,.0265,.004602,.026097,0.0*
1,1,.006,.004602,.026097*
20,1,.006,.004602,.026097,.009064,.024902,0.0*
1,1,.006,.009064,.024902*
20,1,.006,.009064,.024902,.01325,.02295,0.0*
1,1,.006,.01325,.02295*
20,1,.006,.01325,.02295,.017034,.0203,0.0*
1,1,.006,.017034,.0203*
20,1,.006,.017034,.0203,.0203,.017034,0.0*
1,1,.006,.0203,.017034*
20,1,.006,.0203,.017034,.02295,.01325,0.0*
1,1,.006,.02295,.01325*
20,1,.006,.02295,.01325,.024902,.009064,0.0*
1,1,.006,.024902,.009064*
20,1,.006,.024902,.009064,.026097,.004602,0.0*
1,1,.006,.026097,.004602*
20,1,.006,.026097,.004602,.0265,0.0,0.0*
1,1,.006,.0265,0.0*
1,1,.006,-.01325,-.01325*
20,1,.006,-.01325,-.01325,-.01325,.01325,0.0*
1,1,.006,-.01325,.01325*
20,1,.006,-.01325,.01325,-.01855,.00795,0.0*
1,1,.006,-.01855,.00795*
1,1,.006,-.01855,-.01325*
20,1,.006,-.01855,-.01325,-.00795,-.01325,0.0*
1,1,.006,-.00795,-.01325*
1,1,.006,.01326,-.01325*
20,1,.006,.01326,-.01325,.01326,.01325,0.0*
1,1,.006,.01326,.01325*
20,1,.006,.01326,.01325,.00796,.00795,0.0*
1,1,.006,.00796,.00795*
1,1,.006,.00796,-.01325*
20,1,.006,.00796,-.01325,.01856,-.01325,0.0*
1,1,.006,.01856,-.01325*
%
%ADD18MACRO18*%
%AMMACRO21*
1,1,.006,.025,.01875*
20,1,.006,.025,.01875,.025,-.01875,0.0*
1,1,.006,.025,-.01875*
20,1,.006,.025,-.01875,-.025,-.01875,0.0*
1,1,.006,-.025,-.01875*
20,1,.006,-.025,-.01875,-.025,.01875,0.0*
1,1,.006,-.025,.01875*
20,1,.006,-.025,.01875,.025,.01875,0.0*
1,1,.006,.025,.01875*
1,1,.006,-.00938,-.00937*
20,1,.006,-.00938,-.00937,-.00938,.00938,0.0*
1,1,.006,-.00938,.00938*
20,1,.006,-.00938,.00938,-.01313,.00563,0.0*
1,1,.006,-.01313,.00563*
1,1,.006,-.01313,-.00937*
20,1,.006,-.01313,-.00937,-.00563,-.00937,0.0*
1,1,.006,-.00563,-.00937*
1,1,.006,.00938,.00938*
20,1,.006,.00938,.00938,.00688,.00876,0.0*
1,1,.006,.00688,.00876*
20,1,.006,.00688,.00876,.00501,.00719,0.0*
1,1,.006,.00501,.00719*
20,1,.006,.00501,.00719,.00376,.00532,0.0*
1,1,.006,.00376,.00532*
20,1,.006,.00376,.00532,.00282,.00282,0.0*
1,1,.006,.00282,.00282*
20,1,.006,.00282,.00282,.00251,0.0,0.0*
1,1,.006,.00251,0.0*
20,1,.006,.00251,0.0,.00282,-.00281,0.0*
1,1,.006,.00282,-.00281*
20,1,.006,.00282,-.00281,.00376,-.00531,0.0*
1,1,.006,.00376,-.00531*
20,1,.006,.00376,-.00531,.00501,-.00718,0.0*
1,1,.006,.00501,-.00718*
20,1,.006,.00501,-.00718,.00688,-.00875,0.0*
1,1,.006,.00688,-.00875*
20,1,.006,.00688,-.00875,.00938,-.00937,0.0*
1,1,.006,.00938,-.00937*
20,1,.006,.00938,-.00937,.01188,-.00875,0.0*
1,1,.006,.01188,-.00875*
20,1,.006,.01188,-.00875,.01376,-.00718,0.0*
1,1,.006,.01376,-.00718*
20,1,.006,.01376,-.00718,.01501,-.00531,0.0*
1,1,.006,.01501,-.00531*
20,1,.006,.01501,-.00531,.01595,-.00281,0.0*
1,1,.006,.01595,-.00281*
20,1,.006,.01595,-.00281,.01626,0.0,0.0*
1,1,.006,.01626,0.0*
20,1,.006,.01626,0.0,.01595,.00282,0.0*
1,1,.006,.01595,.00282*
20,1,.006,.01595,.00282,.01501,.00532,0.0*
1,1,.006,.01501,.00532*
20,1,.006,.01501,.00532,.01376,.00719,0.0*
1,1,.006,.01376,.00719*
20,1,.006,.01376,.00719,.01188,.00876,0.0*
1,1,.006,.01188,.00876*
20,1,.006,.01188,.00876,.00938,.00938,0.0*
1,1,.006,.00938,.00938*
%
%ADD21MACRO21*%
%AMMACRO11*
1,1,.006,-.02075,.06225*
20,1,.006,-.02075,.06225,.02075,.06225,0.0*
1,1,.006,.02075,.06225*
20,1,.006,.02075,.06225,.03156,.061304,0.0*
1,1,.006,.03156,.061304*
20,1,.006,.03156,.061304,.042041,.058496,0.0*
1,1,.006,.042041,.058496*
20,1,.006,.042041,.058496,.051875,.05391,0.0*
1,1,.006,.051875,.05391*
20,1,.006,.051875,.05391,.060764,.047686,0.0*
1,1,.006,.060764,.047686*
20,1,.006,.060764,.047686,.068436,.040014,0.0*
1,1,.006,.068436,.040014*
20,1,.006,.068436,.040014,.07466,.031125,0.0*
1,1,.006,.07466,.031125*
20,1,.006,.07466,.031125,.079246,.021291,0.0*
1,1,.006,.079246,.021291*
20,1,.006,.079246,.021291,.082054,.01081,0.0*
1,1,.006,.082054,.01081*
20,1,.006,.082054,.01081,.083,0.0,0.0*
1,1,.006,.083,0.0*
20,1,.006,.083,0.0,.082054,-.01081,0.0*
1,1,.006,.082054,-.01081*
20,1,.006,.082054,-.01081,.079246,-.021291,0.0*
1,1,.006,.079246,-.021291*
20,1,.006,.079246,-.021291,.07466,-.031125,0.0*
1,1,.006,.07466,-.031125*
20,1,.006,.07466,-.031125,.068436,-.040014,0.0*
1,1,.006,.068436,-.040014*
20,1,.006,.068436,-.040014,.060764,-.047686,0.0*
1,1,.006,.060764,-.047686*
20,1,.006,.060764,-.047686,.051875,-.05391,0.0*
1,1,.006,.051875,-.05391*
20,1,.006,.051875,-.05391,.042041,-.058496,0.0*
1,1,.006,.042041,-.058496*
20,1,.006,.042041,-.058496,.03156,-.061304,0.0*
1,1,.006,.03156,-.061304*
20,1,.006,.03156,-.061304,.02075,-.06225,0.0*
1,1,.006,.02075,-.06225*
20,1,.006,.02075,-.06225,-.02075,-.06225,0.0*
1,1,.006,-.02075,-.06225*
20,1,.006,-.02075,-.06225,-.03156,-.061304,0.0*
1,1,.006,-.03156,-.061304*
20,1,.006,-.03156,-.061304,-.042041,-.058496,0.0*
1,1,.006,-.042041,-.058496*
20,1,.006,-.042041,-.058496,-.051875,-.05391,0.0*
1,1,.006,-.051875,-.05391*
20,1,.006,-.051875,-.05391,-.060764,-.047686,0.0*
1,1,.006,-.060764,-.047686*
20,1,.006,-.060764,-.047686,-.068436,-.040014,0.0*
1,1,.006,-.068436,-.040014*
20,1,.006,-.068436,-.040014,-.07466,-.031125,0.0*
1,1,.006,-.07466,-.031125*
20,1,.006,-.07466,-.031125,-.079246,-.021291,0.0*
1,1,.006,-.079246,-.021291*
20,1,.006,-.079246,-.021291,-.082054,-.01081,0.0*
1,1,.006,-.082054,-.01081*
20,1,.006,-.082054,-.01081,-.083,0.0,0.0*
1,1,.006,-.083,0.0*
20,1,.006,-.083,0.0,-.082054,.01081,0.0*
1,1,.006,-.082054,.01081*
20,1,.006,-.082054,.01081,-.079246,.021291,0.0*
1,1,.006,-.079246,.021291*
20,1,.006,-.079246,.021291,-.07466,.031125,0.0*
1,1,.006,-.07466,.031125*
20,1,.006,-.07466,.031125,-.068436,.040014,0.0*
1,1,.006,-.068436,.040014*
20,1,.006,-.068436,.040014,-.060764,.047686,0.0*
1,1,.006,-.060764,.047686*
20,1,.006,-.060764,.047686,-.051875,.05391,0.0*
1,1,.006,-.051875,.05391*
20,1,.006,-.051875,.05391,-.042041,.058496,0.0*
1,1,.006,-.042041,.058496*
20,1,.006,-.042041,.058496,-.03156,.061304,0.0*
1,1,.006,-.03156,.061304*
20,1,.006,-.03156,.061304,-.02075,.06225,0.0*
1,1,.006,-.02075,.06225*
1,1,.006,0.0,-.03112*
20,1,.006,0.0,-.03112,.00727,-.03008,0.0*
1,1,.006,.00727,-.03008*
20,1,.006,.00727,-.03008,.01557,-.02697,0.0*
1,1,.006,.01557,-.02697*
20,1,.006,.01557,-.02697,.02076,-.02178,0.0*
1,1,.006,.02076,-.02178*
20,1,.006,.02076,-.02178,.02283,-.01452,0.0*
1,1,.006,.02283,-.01452*
20,1,.006,.02283,-.01452,.02076,-.00726,0.0*
1,1,.006,.02076,-.00726*
20,1,.006,.02076,-.00726,.01453,-.00103,0.0*
1,1,.006,.01453,-.00103*
20,1,.006,.01453,-.00103,.00519,.00208,0.0*
1,1,.006,.00519,.00208*
20,1,.006,.00519,.00208,-.00518,.00208,0.0*
1,1,.006,-.00518,.00208*
20,1,.006,-.00518,.00208,-.01141,.00416,0.0*
1,1,.006,-.01141,.00416*
20,1,.006,-.01141,.00416,-.0166,.00934,0.0*
1,1,.006,-.0166,.00934*
20,1,.006,-.0166,.00934,-.01867,.0166,0.0*
1,1,.006,-.01867,.0166*
20,1,.006,-.01867,.0166,-.01556,.02387,0.0*
1,1,.006,-.01556,.02387*
20,1,.006,-.01556,.02387,-.0083,.02906,0.0*
1,1,.006,-.0083,.02906*
20,1,.006,-.0083,.02906,0.0,.03113,0.0*
1,1,.006,0.0,.03113*
20,1,.006,0.0,.03113,.0083,.02906,0.0*
1,1,.006,.0083,.02906*
20,1,.006,.0083,.02906,.01557,.02387,0.0*
1,1,.006,.01557,.02387*
20,1,.006,.01557,.02387,.01868,.0166,0.0*
1,1,.006,.01868,.0166*
20,1,.006,.01868,.0166,.0166,.00934,0.0*
1,1,.006,.0166,.00934*
20,1,.006,.0166,.00934,.01142,.00416,0.0*
1,1,.006,.01142,.00416*
20,1,.006,.01142,.00416,.00519,.00208,0.0*
1,1,.006,.00519,.00208*
20,1,.006,.00519,.00208,-.00518,.00208,0.0*
1,1,.006,-.00518,.00208*
20,1,.006,-.00518,.00208,-.01452,-.00103,0.0*
1,1,.006,-.01452,-.00103*
20,1,.006,-.01452,-.00103,-.02075,-.00726,0.0*
1,1,.006,-.02075,-.00726*
20,1,.006,-.02075,-.00726,-.02282,-.01452,0.0*
1,1,.006,-.02282,-.01452*
20,1,.006,-.02282,-.01452,-.02075,-.02178,0.0*
1,1,.006,-.02075,-.02178*
20,1,.006,-.02075,-.02178,-.01556,-.02697,0.0*
1,1,.006,-.01556,-.02697*
20,1,.006,-.01556,-.02697,-.00726,-.03008,0.0*
1,1,.006,-.00726,-.03008*
20,1,.006,-.00726,-.03008,0.0,-.03112,0.0*
1,1,.006,0.0,-.03112*
%
%ADD11MACRO11*%
%AMMACRO20*
1,1,.006,-.018,.006*
20,1,.006,-.018,.006,-.017727,.009126,0.0*
1,1,.006,-.017727,.009126*
20,1,.006,-.017727,.009126,-.016914,.012156,0.0*
1,1,.006,-.016914,.012156*
20,1,.006,-.016914,.012156,-.015588,.015,0.0*
1,1,.006,-.015588,.015*
20,1,.006,-.015588,.015,-.013789,.01757,0.0*
1,1,.006,-.013789,.01757*
20,1,.006,-.013789,.01757,-.01157,.019789,0.0*
1,1,.006,-.01157,.019789*
20,1,.006,-.01157,.019789,-.009,.021588,0.0*
1,1,.006,-.009,.021588*
20,1,.006,-.009,.021588,-.006156,.022914,0.0*
1,1,.006,-.006156,.022914*
20,1,.006,-.006156,.022914,-.003126,.023727,0.0*
1,1,.006,-.003126,.023727*
20,1,.006,-.003126,.023727,0.0,.024,0.0*
1,1,.006,0.0,.024*
20,1,.006,0.0,.024,.003126,.023727,0.0*
1,1,.006,.003126,.023727*
20,1,.006,.003126,.023727,.006156,.022914,0.0*
1,1,.006,.006156,.022914*
20,1,.006,.006156,.022914,.009,.021588,0.0*
1,1,.006,.009,.021588*
20,1,.006,.009,.021588,.01157,.019789,0.0*
1,1,.006,.01157,.019789*
20,1,.006,.01157,.019789,.013789,.01757,0.0*
1,1,.006,.013789,.01757*
20,1,.006,.013789,.01757,.015588,.015,0.0*
1,1,.006,.015588,.015*
20,1,.006,.015588,.015,.016914,.012156,0.0*
1,1,.006,.016914,.012156*
20,1,.006,.016914,.012156,.017727,.009126,0.0*
1,1,.006,.017727,.009126*
20,1,.006,.017727,.009126,.018,.006,0.0*
1,1,.006,.018,.006*
20,1,.006,.018,.006,.018,-.006,0.0*
1,1,.006,.018,-.006*
20,1,.006,.018,-.006,.017727,-.009126,0.0*
1,1,.006,.017727,-.009126*
20,1,.006,.017727,-.009126,.016914,-.012156,0.0*
1,1,.006,.016914,-.012156*
20,1,.006,.016914,-.012156,.015588,-.015,0.0*
1,1,.006,.015588,-.015*
20,1,.006,.015588,-.015,.013789,-.01757,0.0*
1,1,.006,.013789,-.01757*
20,1,.006,.013789,-.01757,.01157,-.019789,0.0*
1,1,.006,.01157,-.019789*
20,1,.006,.01157,-.019789,.009,-.021588,0.0*
1,1,.006,.009,-.021588*
20,1,.006,.009,-.021588,.006156,-.022914,0.0*
1,1,.006,.006156,-.022914*
20,1,.006,.006156,-.022914,.003126,-.023727,0.0*
1,1,.006,.003126,-.023727*
20,1,.006,.003126,-.023727,0.0,-.024,0.0*
1,1,.006,0.0,-.024*
20,1,.006,0.0,-.024,-.003126,-.023727,0.0*
1,1,.006,-.003126,-.023727*
20,1,.006,-.003126,-.023727,-.006156,-.022914,0.0*
1,1,.006,-.006156,-.022914*
20,1,.006,-.006156,-.022914,-.009,-.021588,0.0*
1,1,.006,-.009,-.021588*
20,1,.006,-.009,-.021588,-.01157,-.019789,0.0*
1,1,.006,-.01157,-.019789*
20,1,.006,-.01157,-.019789,-.013789,-.01757,0.0*
1,1,.006,-.013789,-.01757*
20,1,.006,-.013789,-.01757,-.015588,-.015,0.0*
1,1,.006,-.015588,-.015*
20,1,.006,-.015588,-.015,-.016914,-.012156,0.0*
1,1,.006,-.016914,-.012156*
20,1,.006,-.016914,-.012156,-.017727,-.009126,0.0*
1,1,.006,-.017727,-.009126*
20,1,.006,-.017727,-.009126,-.018,-.006,0.0*
1,1,.006,-.018,-.006*
20,1,.006,-.018,-.006,-.018,.006,0.0*
1,1,.006,-.018,.006*
1,1,.006,-.0051,-.0069*
20,1,.006,-.0051,-.0069,-.003,-.0084,0.0*
1,1,.006,-.003,-.0084*
20,1,.006,-.003,-.0084,-.0006,-.009,0.0*
1,1,.006,-.0006,-.009*
20,1,.006,-.0006,-.009,.0018,-.0084,0.0*
1,1,.006,.0018,-.0084*
20,1,.006,.0018,-.0084,.0039,-.0066,0.0*
1,1,.006,.0039,-.0066*
20,1,.006,.0039,-.0066,.0054,-.0039,0.0*
1,1,.006,.0054,-.0039*
20,1,.006,.0054,-.0039,.006,-.0012,0.0*
1,1,.006,.006,-.0012*
20,1,.006,.006,-.0012,.006,.0021,0.0*
1,1,.006,.006,.0021*
20,1,.006,.006,.0021,.0054,.0048,0.0*
1,1,.006,.0054,.0048*
20,1,.006,.0054,.0048,.0039,.0072,0.0*
1,1,.006,.0039,.0072*
20,1,.006,.0039,.0072,.0021,.0084,0.0*
1,1,.006,.0021,.0084*
20,1,.006,.0021,.0084,0.0,.009,0.0*
1,1,.006,0.0,.009*
20,1,.006,0.0,.009,-.0024,.0084,0.0*
1,1,.006,-.0024,.0084*
20,1,.006,-.0024,.0084,-.0042,.0072,0.0*
1,1,.006,-.0042,.0072*
20,1,.006,-.0042,.0072,-.0054,.0054,0.0*
1,1,.006,-.0054,.0054*
20,1,.006,-.0054,.0054,-.006,.003,0.0*
1,1,.006,-.006,.003*
20,1,.006,-.006,.003,-.0054,.0009,0.0*
1,1,.006,-.0054,.0009*
20,1,.006,-.0054,.0009,-.0039,-.0012,0.0*
1,1,.006,-.0039,-.0012*
20,1,.006,-.0039,-.0012,-.0021,-.0024,0.0*
1,1,.006,-.0021,-.0024*
20,1,.006,-.0021,-.0024,0.0,-.0027,0.0*
1,1,.006,0.0,-.0027*
20,1,.006,0.0,-.0027,.0024,-.0021,0.0*
1,1,.006,.0024,-.0021*
20,1,.006,.0024,-.0021,.0042,-.0006,0.0*
1,1,.006,.0042,-.0006*
20,1,.006,.0042,-.0006,.006,.0021,0.0*
1,1,.006,.006,.0021*
%
%ADD20MACRO20*%
%ADD23C,.02*%
%ADD24C,.006*%
G75*
%LPD*%
G75*
G54D10*
X-14755Y415558D03*
X-12454Y45507D03*
X17715Y44095D03*
X29461Y718854D03*
X141466Y655356D03*
X395935Y76695D03*
X508569Y15093D03*
X525590Y240944D03*
X552795Y40157D03*
X554126Y315939D03*
Y685624D03*
X658381Y378446D03*
G54D20*
X312657Y66142D03*
Y107716D03*
X658381Y453446D03*
G54D11*
X15748Y15827D03*
X551181Y242913D03*
X658381Y478446D03*
G54D21*
X473149Y79094D03*
X532205D03*
X658381Y428446D03*
G54D12*
X15748Y67008D03*
X303150Y13780D03*
Y242913D03*
X551181Y13780D03*
X658381Y503446D03*
G54D22*
X484960Y86811D03*
X496771D03*
X508583D03*
X520394D03*
X658381Y553446D03*
G54D13*
X5500Y48299D03*
X7960Y85839D03*
X42701Y5500D03*
X48316Y32530D03*
X44316D03*
Y28681D03*
X48316D03*
X44278Y24717D03*
X48278D03*
X49374Y56390D03*
X45374D03*
X45336Y52426D03*
X49336D03*
X41000Y79500D03*
Y75500D03*
X37000Y79500D03*
Y75500D03*
X49374Y60239D03*
X45374D03*
X27960Y85839D03*
X63713Y48425D03*
X65006Y43434D03*
X60469Y79819D03*
X67960Y85839D03*
X56667Y83351D03*
X60393Y83934D03*
X52667Y83351D03*
X87960Y85839D03*
X107960D03*
X127960D03*
X147960D03*
X167960D03*
X207675Y38907D03*
X204000Y82000D03*
X208000D03*
Y86000D03*
X204000D03*
X187960Y85839D03*
X214906Y39494D03*
X211337Y38963D03*
X242500Y27000D03*
X246500D03*
X243000Y47500D03*
X247000D03*
X244727Y76591D03*
X244870Y80370D03*
X248866Y76464D03*
X248811Y80272D03*
X261719Y52314D03*
X261774Y48506D03*
X261840Y42259D03*
X261924Y38480D03*
X258240Y42259D03*
X258174Y48506D03*
X258119Y52314D03*
X258324Y38480D03*
X281221Y33971D03*
X286638Y33917D03*
X282148Y51376D03*
X282093Y55184D03*
X278462Y51437D03*
X278407Y55245D03*
X281964Y47752D03*
X278278Y47813D03*
X284292Y61505D03*
X280555Y61542D03*
X284798Y149063D03*
X299300Y144500D03*
X284905Y160541D03*
X284940Y156881D03*
X284798Y152687D03*
X289800Y165000D03*
X300000Y164900D03*
X297698Y191563D03*
Y195187D03*
X279122Y174213D03*
Y194213D03*
X297840Y199381D03*
X297805Y203041D03*
X279122Y214213D03*
Y234213D03*
X282142Y251193D03*
X322701Y5500D03*
X321373Y56703D03*
X303700Y140700D03*
X315048Y133300D03*
X302000Y133500D03*
X301913Y129821D03*
X303000Y144400D03*
X309500Y145000D03*
X303600Y164800D03*
X320332Y160022D03*
X316332D03*
Y164522D03*
X320332D03*
X316332Y155668D03*
X320332D03*
X316438Y151436D03*
X320438D03*
X318500Y193500D03*
X314500D03*
X318500Y188500D03*
X314500D03*
X300754Y205956D03*
X304000Y213000D03*
X314454Y213250D03*
X314500Y203500D03*
X318500D03*
Y198500D03*
X314500D03*
X322142Y251193D03*
X332666Y27700D03*
X332778Y20000D03*
X328508Y41629D03*
X328424Y45408D03*
X332508Y41629D03*
X332424Y45408D03*
X332565Y49028D03*
X332614Y52663D03*
X328565Y49028D03*
X328614Y52663D03*
X336698Y154738D03*
X340698D03*
X340779Y158381D03*
Y162024D03*
X336779D03*
Y158381D03*
X340779Y165718D03*
X336779D03*
X326423Y183632D03*
X332000Y183500D03*
X339000Y193500D03*
X335000D03*
X326000Y217500D03*
X335000Y203500D03*
X339000D03*
Y198500D03*
X335000D03*
X342142Y251193D03*
X357672Y4602D03*
X347421Y8568D03*
X350479Y10768D03*
X345690Y20300D03*
X353229Y52810D03*
X349229D03*
X353095Y45538D03*
X353094Y49157D03*
X352971Y41813D03*
X349095Y45538D03*
X349094Y49157D03*
X348971Y41813D03*
X364750Y37750D03*
X354580Y102351D03*
X350569Y102263D03*
X358824Y108849D03*
X352501Y105640D03*
X350827Y108976D03*
X348696Y105396D03*
X356501Y105640D03*
X354827Y108976D03*
X362142Y251193D03*
X382142D03*
X402142D03*
X422142D03*
X442142D03*
X471445Y93346D03*
X476600Y227250D03*
X480101Y230616D03*
X462142Y251193D03*
X502868Y166448D03*
X483700Y230522D03*
X502142Y251193D03*
X482142D03*
X519980Y226295D03*
X523642Y226351D03*
X520017Y230070D03*
X523642Y230014D03*
X522142Y251193D03*
X538965Y41992D03*
Y61992D03*
X559461Y68512D03*
Y88512D03*
Y108512D03*
Y148512D03*
Y128512D03*
Y168512D03*
Y188512D03*
Y208512D03*
X658381Y628446D03*
G54D23*
G01X-139981Y-146685D02*
G02I-12000J0D01*
G01X-145131D02*
G02I-6850J0D01*
G01X-135981D02*
X-167981D01*
G01X-135981Y-162685D02*
Y-242685D01*
G01D02*
X971619D01*
G01X-135981Y-198185D02*
X971619D01*
G01X-151981Y-162685D02*
Y-130685D01*
G01X-135981Y-162685D02*
X971619D01*
G01X184119D02*
Y-242685D01*
G01X321619Y-162685D02*
Y-242685D01*
G01X436619Y-162685D02*
Y-242685D01*
G01X604119Y-162685D02*
Y-242685D01*
G01X774119Y-162685D02*
Y-242685D01*
G01X971619Y-162685D02*
Y-242685D01*
G01X999619Y-146685D02*
G02I-12000J0D01*
G01X1003619D02*
X971619D01*
G01X994469D02*
G02I-6850J0D01*
G01X987619Y-162685D02*
Y-130685D01*
G54D14*
X68112Y15039D03*
Y59528D03*
X233462Y15039D03*
Y59528D03*
X359156Y142992D03*
Y208740D03*
X524506Y142992D03*
Y208740D03*
X658381Y528446D03*
G54D24*
G01X-116181Y-215185D02*
Y-232685D01*
G01X-121203Y-215185D02*
X-111159D01*
G01X-103048Y-232685D02*
Y-215185D01*
X-97808D01*
X-96061Y-216060D01*
X-94751Y-218102D01*
X-94314Y-220435D01*
X-94751Y-222768D01*
X-95843Y-224518D01*
X-97808Y-225394D01*
X-103048D01*
G01X-58878Y-216644D02*
X-60188Y-215768D01*
X-61716Y-215185D01*
X-63463D01*
X-65428Y-216060D01*
X-66956Y-217518D01*
X-68048Y-219269D01*
X-68921Y-222185D01*
X-69140Y-224810D01*
X-68703Y-227435D01*
X-68048Y-229185D01*
X-66738Y-230935D01*
X-65209Y-232102D01*
X-63681Y-232685D01*
X-62153D01*
X-60624Y-232102D01*
X-59314Y-231227D01*
X-58222Y-230061D01*
G01X-49893Y-232685D02*
Y-215185D01*
G01Y-223643D02*
X-48801Y-222185D01*
X-47709Y-221310D01*
X-45963Y-221019D01*
X-44653Y-221310D01*
X-43124Y-222477D01*
X-42469Y-224227D01*
Y-232685D01*
G01X-24751D02*
Y-221019D01*
G01Y-223060D02*
X-25624Y-221894D01*
X-26935Y-221310D01*
X-28463Y-221019D01*
X-29991Y-221602D01*
X-31301Y-222768D01*
X-32175Y-224518D01*
X-32611Y-226852D01*
X-32175Y-229185D01*
X-31301Y-230935D01*
X-29991Y-232102D01*
X-28463Y-232685D01*
X-26935Y-232393D01*
X-25624Y-231519D01*
X-24751Y-230352D01*
G01X-14893Y-232685D02*
Y-221019D01*
G01Y-223935D02*
X-14019Y-222477D01*
X-12709Y-221310D01*
X-10963Y-221019D01*
X-9435Y-221310D01*
X-8124Y-222477D01*
X-7469Y-224518D01*
Y-232685D01*
G01X2607D02*
Y-221019D01*
G01Y-223935D02*
X3481Y-222477D01*
X4791Y-221310D01*
X6537Y-221019D01*
X8065Y-221310D01*
X9376Y-222477D01*
X10031Y-224518D01*
Y-232685D01*
G01X20544Y-224810D02*
X27531D01*
X26876Y-222768D01*
X25784Y-221602D01*
X24256Y-221019D01*
X22727Y-221310D01*
X21417Y-222185D01*
X20544Y-224227D01*
X20107Y-225977D01*
Y-227727D01*
X20544Y-229477D01*
X21636Y-231227D01*
X22946Y-232393D01*
X24474Y-232685D01*
X26002Y-232102D01*
X27531Y-230352D01*
G01X41319Y-232685D02*
Y-215185D01*
G01X71734Y-232685D02*
Y-215185D01*
G01X80904D02*
Y-232685D01*
G01Y-223935D02*
X71734D01*
G01X89016Y-232685D02*
Y-215185D01*
X93382D01*
X95129Y-216060D01*
X96439Y-217227D01*
X97531Y-218976D01*
X98404Y-221019D01*
X98622Y-223935D01*
X98404Y-226852D01*
X97531Y-228894D01*
X96439Y-230644D01*
X95129Y-231810D01*
X93382Y-232685D01*
X89016D01*
G01X106516D02*
Y-215185D01*
X110882D01*
X112629Y-216060D01*
X113939Y-217227D01*
X115031Y-218976D01*
X115904Y-221019D01*
X116122Y-223935D01*
X115904Y-226852D01*
X115031Y-228894D01*
X113939Y-230644D01*
X112629Y-231810D01*
X110882Y-232685D01*
X106516D01*
G01X148065Y-223352D02*
X148939Y-222477D01*
X149594Y-221019D01*
X150031Y-218976D01*
X149594Y-217227D01*
X148721Y-216060D01*
X147192Y-215185D01*
X141297D01*
Y-232685D01*
X148502D01*
X150031Y-231519D01*
X150904Y-229768D01*
X151341Y-227727D01*
X150904Y-225685D01*
X149594Y-223935D01*
X148065Y-223352D01*
X141297D01*
G01X159452Y-232685D02*
Y-215185D01*
X164692D01*
X166439Y-216060D01*
X167749Y-218102D01*
X168186Y-220435D01*
X167749Y-222768D01*
X166657Y-224518D01*
X164692Y-225394D01*
X159452D01*
G01X-16858Y-187685D02*
Y-170185D01*
X-11181Y-184768D01*
X-5504Y-170185D01*
Y-187685D01*
G01X6319D02*
X5009Y-187393D01*
X3699Y-186227D01*
X2825Y-184185D01*
X2389Y-181852D01*
X2825Y-179518D01*
X3699Y-177477D01*
X5009Y-176310D01*
X6319Y-176019D01*
X7629Y-176310D01*
X8939Y-177477D01*
X9812Y-179518D01*
X10031Y-181852D01*
X9812Y-184185D01*
X8939Y-186227D01*
X7629Y-187393D01*
X6319Y-187685D01*
G01X27749Y-170185D02*
Y-187685D01*
G01Y-185061D02*
X26876Y-186519D01*
X25565Y-187393D01*
X24037Y-187685D01*
X22291Y-187102D01*
X20981Y-185644D01*
X20107Y-183894D01*
X19889Y-181852D01*
X20107Y-179810D01*
X20981Y-178060D01*
X22291Y-176602D01*
X24037Y-176019D01*
X25565Y-176310D01*
X26657Y-176894D01*
X27749Y-178060D01*
G01X38044Y-179810D02*
X45031D01*
X44376Y-177768D01*
X43284Y-176602D01*
X41756Y-176019D01*
X40227Y-176310D01*
X38917Y-177185D01*
X38044Y-179227D01*
X37607Y-180977D01*
Y-182727D01*
X38044Y-184477D01*
X39136Y-186227D01*
X40446Y-187393D01*
X41974Y-187685D01*
X43502Y-187102D01*
X45031Y-185352D01*
G01X58819Y-187685D02*
Y-170185D01*
G01X204702Y-187685D02*
Y-170185D01*
X209942D01*
X211689Y-171060D01*
X212999Y-173102D01*
X213436Y-175435D01*
X212999Y-177768D01*
X211907Y-179518D01*
X209942Y-180394D01*
X204702D01*
G01X231372Y-171644D02*
X230062Y-170768D01*
X228534Y-170185D01*
X226787D01*
X224822Y-171060D01*
X223294Y-172518D01*
X222202Y-174269D01*
X221329Y-177185D01*
X221110Y-179810D01*
X221547Y-182435D01*
X222202Y-184185D01*
X223512Y-185935D01*
X225041Y-187102D01*
X226569Y-187685D01*
X228097D01*
X229626Y-187102D01*
X230936Y-186227D01*
X232028Y-185061D01*
G01X245815Y-178352D02*
X246689Y-177477D01*
X247344Y-176019D01*
X247781Y-173976D01*
X247344Y-172227D01*
X246471Y-171060D01*
X244942Y-170185D01*
X239047D01*
Y-187685D01*
X246252D01*
X247781Y-186519D01*
X248654Y-184768D01*
X249091Y-182727D01*
X248654Y-180685D01*
X247344Y-178935D01*
X245815Y-178352D01*
X239047D01*
G01X255019Y-193518D02*
X268119D01*
G01X274047Y-187685D02*
Y-170185D01*
X284091Y-187685D01*
Y-170185D01*
G01X296569Y-187685D02*
X294822Y-187393D01*
X293294Y-186227D01*
X291984Y-184477D01*
X291110Y-182435D01*
X290674Y-180102D01*
Y-177768D01*
X291110Y-175435D01*
X291984Y-173393D01*
X293294Y-171644D01*
X294822Y-170477D01*
X296569Y-170185D01*
X298315Y-170477D01*
X299844Y-171644D01*
X301154Y-173393D01*
X302028Y-175435D01*
X302464Y-177768D01*
Y-180102D01*
X302028Y-182435D01*
X301154Y-184477D01*
X299844Y-186227D01*
X298315Y-187393D01*
X296569Y-187685D01*
G01X217819Y-232685D02*
Y-215185D01*
X215199Y-218685D01*
G01Y-232685D02*
X220439D01*
G01X234882D02*
X235319Y-228894D01*
X235974Y-225685D01*
X236847Y-222768D01*
X237939Y-219560D01*
X239686Y-215185D01*
X230952D01*
G01X248016Y-229185D02*
X249325Y-231227D01*
X251072Y-232393D01*
X253037Y-232685D01*
X254784Y-232393D01*
X256531Y-230935D01*
X257622Y-229185D01*
X257841Y-227435D01*
X257404Y-225394D01*
X255876Y-223935D01*
X254347Y-223352D01*
X252382D01*
G01X254347D02*
X255657Y-222477D01*
X256749Y-221019D01*
X257186Y-219269D01*
X256749Y-217518D01*
X255657Y-216060D01*
X253692Y-215185D01*
X251727Y-215477D01*
X249762Y-216644D01*
G01X270319Y-215185D02*
X268572Y-215768D01*
X267262Y-217227D01*
X266389Y-218976D01*
X265734Y-221310D01*
X265516Y-223935D01*
X265734Y-226560D01*
X266389Y-228894D01*
X267262Y-230644D01*
X268572Y-232102D01*
X270319Y-232685D01*
X272065Y-232102D01*
X273376Y-230644D01*
X274249Y-228894D01*
X274904Y-226560D01*
X275122Y-223935D01*
X274904Y-221310D01*
X274249Y-218976D01*
X273376Y-217227D01*
X272065Y-215768D01*
X270319Y-215185D01*
G01X287819Y-232685D02*
Y-215185D01*
X285199Y-218685D01*
G01Y-232685D02*
X290439D01*
G01X295725Y66571D02*
X291257Y75529D01*
G01X294836Y71715D02*
X295725Y66571D01*
X292151Y70376D01*
X294836Y71715D01*
G01X293572Y64571D02*
X297372D01*
G03Y66571I0J1000D01*
G01X293572D01*
G03Y64571I0J-1000D01*
G01X295591Y107287D02*
X291857Y97529D01*
G01X292403Y103153D02*
X295591Y107287D01*
X295205Y102081D01*
X292403Y103153D01*
G01X293572Y107287D02*
X297372D01*
G03Y109287I0J1000D01*
G01X293572D01*
G03Y107287I0J-1000D01*
G01X333481Y65708D02*
X340457Y74929D01*
G01X337694Y68790D02*
X333481Y65708D01*
X335301Y70600D01*
X337694Y68790D01*
G01X328690Y64571D02*
X332490D01*
G03Y66571I0J1000D01*
G01X328690D01*
G03Y64571I0J-1000D01*
G01X333486Y108375D02*
X340857Y96529D01*
G01X334854Y103337D02*
X333486Y108375D01*
X337401Y104922D01*
X334854Y103337D01*
G01X328690Y107287D02*
X332490D01*
G03Y109287I0J1000D01*
G01X328690D01*
G03Y107287I0J-1000D01*
G01X365784Y-230352D02*
X367531Y-231810D01*
X369496Y-232685D01*
X371242D01*
X372989Y-231810D01*
X374299Y-230352D01*
X374954Y-228310D01*
X374517Y-226269D01*
X373426Y-224518D01*
X371461Y-223352D01*
X368841Y-222768D01*
X367312Y-221602D01*
X366657Y-219560D01*
X367094Y-217518D01*
X368186Y-216060D01*
X369714Y-215185D01*
X371242D01*
X372771Y-215768D01*
X374081Y-217227D01*
G01X382410Y-232685D02*
X387869Y-215185D01*
X393328Y-232685D01*
G01X391362Y-226560D02*
X384375D01*
G01X347410Y-170185D02*
X352869Y-187685D01*
X358328Y-170185D01*
G01X374736Y-187685D02*
X366002D01*
Y-170185D01*
X374736D01*
G01X371242Y-178643D02*
X366002D01*
G01X383502Y-187685D02*
Y-170185D01*
X388961D01*
X390707Y-171060D01*
X391799Y-172227D01*
X392236Y-174560D01*
X391799Y-176894D01*
X390489Y-178352D01*
X388961Y-179227D01*
X383502D01*
G01X388961D02*
X392236Y-187685D01*
G01X405369Y-188268D02*
X404932Y-187977D01*
Y-187393D01*
X405369Y-187102D01*
X405806Y-187393D01*
Y-187977D01*
X405369Y-188268D01*
G01X480516Y-232685D02*
Y-215185D01*
X484882D01*
X486629Y-216060D01*
X487939Y-217227D01*
X489031Y-218976D01*
X489904Y-221019D01*
X490122Y-223935D01*
X489904Y-226852D01*
X489031Y-228894D01*
X487939Y-230644D01*
X486629Y-231810D01*
X484882Y-232685D01*
X480516D01*
G01X498452D02*
Y-215185D01*
X503911D01*
X505657Y-216060D01*
X506749Y-217227D01*
X507186Y-219560D01*
X506749Y-221894D01*
X505439Y-223352D01*
X503911Y-224227D01*
X498452D01*
G01X503911D02*
X507186Y-232685D01*
G01X517699Y-215185D02*
X522939D01*
G01X520319D02*
Y-232685D01*
G01X517699D02*
X522939D01*
G01X533452Y-215185D02*
Y-232685D01*
X542186D01*
G01X550952Y-215185D02*
Y-232685D01*
X559686D01*
G01X480952Y-170185D02*
Y-187685D01*
X489686D01*
G01X506749D02*
Y-176019D01*
G01Y-178060D02*
X505876Y-176894D01*
X504565Y-176310D01*
X503037Y-176019D01*
X501509Y-176602D01*
X500199Y-177768D01*
X499325Y-179518D01*
X498889Y-181852D01*
X499325Y-184185D01*
X500199Y-185935D01*
X501509Y-187102D01*
X503037Y-187685D01*
X504565Y-187393D01*
X505876Y-186519D01*
X506749Y-185352D01*
G01X515734Y-192935D02*
X517044Y-193518D01*
X518791Y-192935D01*
X519882Y-191769D01*
X520756Y-190310D01*
X522065Y-185644D01*
X524904Y-176019D01*
G01X517917D02*
X522065Y-185644D01*
G01X534544Y-179810D02*
X541531D01*
X540876Y-177768D01*
X539784Y-176602D01*
X538256Y-176019D01*
X536727Y-176310D01*
X535417Y-177185D01*
X534544Y-179227D01*
X534107Y-180977D01*
Y-182727D01*
X534544Y-184477D01*
X535636Y-186227D01*
X536946Y-187393D01*
X538474Y-187685D01*
X540002Y-187102D01*
X541531Y-185352D01*
G01X552262Y-187685D02*
Y-176019D01*
G01Y-178352D02*
X553354Y-177185D01*
X554446Y-176310D01*
X555974Y-176019D01*
X557065Y-176310D01*
X558376Y-177185D01*
G01X614516Y310946D02*
Y323446D01*
X621646Y310946D01*
Y323446D01*
G01X630481Y310946D02*
X629551Y311154D01*
X628621Y311987D01*
X628001Y313446D01*
X627691Y315113D01*
X628001Y316779D01*
X628621Y318238D01*
X629551Y319071D01*
X630481Y319279D01*
X631411Y319071D01*
X632341Y318238D01*
X632961Y316779D01*
X633116Y315113D01*
X632961Y313446D01*
X632341Y311987D01*
X631411Y311154D01*
X630481Y310946D01*
G01X642881Y323446D02*
Y310946D01*
G01X640711Y319279D02*
X645051D01*
G01X652956Y316571D02*
X657916D01*
X657451Y318029D01*
X656676Y318863D01*
X655591Y319279D01*
X654506Y319071D01*
X653576Y318446D01*
X652956Y316988D01*
X652646Y315737D01*
Y314488D01*
X652956Y313238D01*
X653731Y311987D01*
X654661Y311154D01*
X655746Y310946D01*
X656831Y311363D01*
X657916Y312612D01*
G01X667681Y310529D02*
X667371Y310738D01*
Y311154D01*
X667681Y311363D01*
X667991Y311154D01*
Y310738D01*
X667681Y310529D01*
G01Y316154D02*
X667371Y316363D01*
Y316779D01*
X667681Y316988D01*
X667991Y316779D01*
Y316363D01*
X667681Y316154D01*
G01X676981Y310946D02*
Y323446D01*
X680856D01*
X682096Y322821D01*
X682871Y321988D01*
X683181Y320321D01*
X682871Y318654D01*
X681941Y317613D01*
X680856Y316988D01*
X676981D01*
G01X680856D02*
X683181Y310946D01*
G01X690156Y316571D02*
X695116D01*
X694651Y318029D01*
X693876Y318863D01*
X692791Y319279D01*
X691706Y319071D01*
X690776Y318446D01*
X690156Y316988D01*
X689846Y315737D01*
Y314488D01*
X690156Y313238D01*
X690931Y311987D01*
X691861Y311154D01*
X692946Y310946D01*
X694031Y311363D01*
X695116Y312612D01*
G01X703951Y310946D02*
Y321571D01*
X704261Y322612D01*
X704881Y323238D01*
X705811Y323446D01*
X706741Y323029D01*
X707206Y321988D01*
G01X705346Y318446D02*
X702246D01*
G01X714956Y316571D02*
X719916D01*
X719451Y318029D01*
X718676Y318863D01*
X717591Y319279D01*
X716506Y319071D01*
X715576Y318446D01*
X714956Y316988D01*
X714646Y315737D01*
Y314488D01*
X714956Y313238D01*
X715731Y311987D01*
X716661Y311154D01*
X717746Y310946D01*
X718831Y311363D01*
X719916Y312612D01*
G01X727511Y310946D02*
Y319279D01*
G01Y317613D02*
X728286Y318446D01*
X729061Y319071D01*
X730146Y319279D01*
X730921Y319071D01*
X731851Y318446D01*
G01X754481Y323446D02*
Y310946D01*
G01X752311Y319279D02*
X756651D01*
G01X766881Y310946D02*
X765951Y311154D01*
X765021Y311987D01*
X764401Y313446D01*
X764091Y315113D01*
X764401Y316779D01*
X765021Y318238D01*
X765951Y319071D01*
X766881Y319279D01*
X767811Y319071D01*
X768741Y318238D01*
X769361Y316779D01*
X769516Y315113D01*
X769361Y313446D01*
X768741Y311987D01*
X767811Y311154D01*
X766881Y310946D01*
G01X788271D02*
Y323446D01*
X791371D01*
X792611Y322821D01*
X793541Y321988D01*
X794316Y320738D01*
X794936Y319279D01*
X795091Y317196D01*
X794936Y315113D01*
X794316Y313654D01*
X793541Y312404D01*
X792611Y311571D01*
X791371Y310946D01*
X788271D01*
G01X800981D02*
Y323446D01*
X804856D01*
X806096Y322821D01*
X806871Y321988D01*
X807181Y320321D01*
X806871Y318654D01*
X805941Y317613D01*
X804856Y316988D01*
X800981D01*
G01X804856D02*
X807181Y310946D01*
G01X814621Y323446D02*
X818341D01*
G01X816481D02*
Y310946D01*
G01X814621D02*
X818341D01*
G01X825781Y323446D02*
Y310946D01*
X831981D01*
G01X838181Y323446D02*
Y310946D01*
X844381D01*
G01X866081D02*
Y323446D01*
G01X881271Y310946D02*
Y319279D01*
G01Y317821D02*
X880651Y318654D01*
X879721Y319071D01*
X878636Y319279D01*
X877551Y318863D01*
X876621Y318029D01*
X876001Y316779D01*
X875691Y315113D01*
X876001Y313446D01*
X876621Y312196D01*
X877551Y311363D01*
X878636Y310946D01*
X879721Y311154D01*
X880651Y311779D01*
X881271Y312612D01*
G01X887626Y307196D02*
X888556Y306779D01*
X889796Y307196D01*
X890571Y308029D01*
X891191Y309071D01*
X892121Y312404D01*
X894136Y319279D01*
G01X889176D02*
X892121Y312404D01*
G01X900956Y316571D02*
X905916D01*
X905451Y318029D01*
X904676Y318863D01*
X903591Y319279D01*
X902506Y319071D01*
X901576Y318446D01*
X900956Y316988D01*
X900646Y315737D01*
Y314488D01*
X900956Y313238D01*
X901731Y311987D01*
X902661Y311154D01*
X903746Y310946D01*
X904831Y311363D01*
X905916Y312612D01*
G01X913511Y310946D02*
Y319279D01*
G01Y317613D02*
X914286Y318446D01*
X915061Y319071D01*
X916146Y319279D01*
X916921Y319071D01*
X917851Y318446D01*
G01X939551Y310946D02*
Y321571D01*
X939861Y322612D01*
X940481Y323238D01*
X941411Y323446D01*
X942341Y323029D01*
X942806Y321988D01*
G01X940946Y318446D02*
X937846D01*
G01X952881Y310946D02*
X951951Y311154D01*
X951021Y311987D01*
X950401Y313446D01*
X950091Y315113D01*
X950401Y316779D01*
X951021Y318238D01*
X951951Y319071D01*
X952881Y319279D01*
X953811Y319071D01*
X954741Y318238D01*
X955361Y316779D01*
X955516Y315113D01*
X955361Y313446D01*
X954741Y311987D01*
X953811Y311154D01*
X952881Y310946D01*
G01X963111D02*
Y319279D01*
G01Y317613D02*
X963886Y318446D01*
X964661Y319071D01*
X965746Y319279D01*
X966521Y319071D01*
X967451Y318446D01*
G01X993181Y310946D02*
X986981D01*
Y323446D01*
X993181D01*
G01X990701Y317404D02*
X986981D01*
G01X999381Y323446D02*
Y310946D01*
X1005581D01*
G01X1011781Y323446D02*
Y310946D01*
X1017981D01*
G01X1025421Y323446D02*
X1029141D01*
G01X1027281D02*
Y310946D01*
G01X1025421D02*
X1029141D01*
G01X1036581D02*
Y323446D01*
X1040301D01*
X1041541Y322821D01*
X1042471Y321363D01*
X1042781Y319696D01*
X1042471Y318029D01*
X1041696Y316779D01*
X1040301Y316154D01*
X1036581D01*
G01X1048826Y312612D02*
X1050066Y311571D01*
X1051461Y310946D01*
X1052701D01*
X1053941Y311571D01*
X1054871Y312612D01*
X1055336Y314071D01*
X1055026Y315529D01*
X1054251Y316779D01*
X1052856Y317613D01*
X1050996Y318029D01*
X1049911Y318863D01*
X1049446Y320321D01*
X1049756Y321779D01*
X1050531Y322821D01*
X1051616Y323446D01*
X1052701D01*
X1053786Y323029D01*
X1054716Y321988D01*
G01X1067581Y310946D02*
X1061381D01*
Y323446D01*
X1067581D01*
G01X1065101Y317404D02*
X1061381D01*
G01X1092071Y323446D02*
Y310946D01*
G01Y312821D02*
X1091451Y311779D01*
X1090521Y311154D01*
X1089436Y310946D01*
X1088196Y311363D01*
X1087266Y312404D01*
X1086646Y313654D01*
X1086491Y315113D01*
X1086646Y316571D01*
X1087266Y317821D01*
X1088196Y318863D01*
X1089436Y319279D01*
X1090521Y319071D01*
X1091296Y318654D01*
X1092071Y317821D01*
G01X1099511Y310946D02*
Y319279D01*
G01Y317613D02*
X1100286Y318446D01*
X1101061Y319071D01*
X1102146Y319279D01*
X1102921Y319071D01*
X1103851Y318446D01*
G01X1114081Y319279D02*
Y310946D01*
G01Y322612D02*
X1113771Y322821D01*
Y323238D01*
X1114081Y323446D01*
X1114391Y323238D01*
Y322821D01*
X1114081Y322612D01*
G01X1126481Y310946D02*
Y323446D01*
G01X1138881Y310946D02*
Y323446D01*
G01X1166471D02*
Y310946D01*
G01Y312821D02*
X1165851Y311779D01*
X1164921Y311154D01*
X1163836Y310946D01*
X1162596Y311363D01*
X1161666Y312404D01*
X1161046Y313654D01*
X1160891Y315113D01*
X1161046Y316571D01*
X1161666Y317821D01*
X1162596Y318863D01*
X1163836Y319279D01*
X1164921Y319071D01*
X1165696Y318654D01*
X1166471Y317821D01*
G01X1176081Y319279D02*
Y310946D01*
G01Y322612D02*
X1175771Y322821D01*
Y323238D01*
X1176081Y323446D01*
X1176391Y323238D01*
Y322821D01*
X1176081Y322612D01*
G01X1186311Y310946D02*
Y319279D01*
G01Y317613D02*
X1187086Y318446D01*
X1187861Y319071D01*
X1188946Y319279D01*
X1189721Y319071D01*
X1190651Y318446D01*
G01X1198556Y316571D02*
X1203516D01*
X1203051Y318029D01*
X1202276Y318863D01*
X1201191Y319279D01*
X1200106Y319071D01*
X1199176Y318446D01*
X1198556Y316988D01*
X1198246Y315737D01*
Y314488D01*
X1198556Y313238D01*
X1199331Y311987D01*
X1200261Y311154D01*
X1201346Y310946D01*
X1202431Y311363D01*
X1203516Y312612D01*
G01X1215761Y318238D02*
X1214676Y319071D01*
X1213746Y319279D01*
X1212506Y318863D01*
X1211576Y318029D01*
X1210956Y316571D01*
X1210801Y315113D01*
X1210956Y313654D01*
X1211576Y312404D01*
X1212506Y311363D01*
X1213746Y310946D01*
X1214831Y311363D01*
X1215761Y312196D01*
G01X1225681Y323446D02*
Y310946D01*
G01X1223511Y319279D02*
X1227851D01*
G01X1238081D02*
Y310946D01*
G01Y322612D02*
X1237771Y322821D01*
Y323238D01*
X1238081Y323446D01*
X1238391Y323238D01*
Y322821D01*
X1238081Y322612D01*
G01X1250481Y310946D02*
X1249551Y311154D01*
X1248621Y311987D01*
X1248001Y313446D01*
X1247691Y315113D01*
X1248001Y316779D01*
X1248621Y318238D01*
X1249551Y319071D01*
X1250481Y319279D01*
X1251411Y319071D01*
X1252341Y318238D01*
X1252961Y316779D01*
X1253116Y315113D01*
X1252961Y313446D01*
X1252341Y311987D01*
X1251411Y311154D01*
X1250481Y310946D01*
G01X1260246D02*
Y319279D01*
G01Y317196D02*
X1260866Y318238D01*
X1261796Y319071D01*
X1263036Y319279D01*
X1264121Y319071D01*
X1265051Y318238D01*
X1265516Y316779D01*
Y310946D01*
G01X613431Y340946D02*
Y740946D01*
X1097031D01*
Y340946D01*
X613431D01*
G01Y365946D02*
X1097031D01*
G01X613431Y390946D02*
X1097031D01*
G01X613431Y415946D02*
X1097031D01*
G01X613431Y440946D02*
X1097031D01*
G01X613431Y465946D02*
X1097031D01*
G01X613431Y490946D02*
X1097031D01*
G01X613431Y515946D02*
X1097031D01*
G01X613431Y540946D02*
X1097031D01*
G01X613431Y565946D02*
X1097031D01*
G01X613431Y590946D02*
X1097031D01*
G01X613431Y615946D02*
X1097031D01*
G01X613431Y640946D02*
X1097031D01*
G01X613431Y665946D02*
X1097031D01*
G01X613431Y690946D02*
X1097031D01*
G01X613431Y715946D02*
X1097031D01*
G01X623066Y-187685D02*
Y-170185D01*
X627432D01*
X629179Y-171060D01*
X630489Y-172227D01*
X631581Y-173976D01*
X632454Y-176019D01*
X632672Y-178935D01*
X632454Y-181852D01*
X631581Y-183894D01*
X630489Y-185644D01*
X629179Y-186810D01*
X627432Y-187685D01*
X623066D01*
G01X642094Y-179810D02*
X649081D01*
X648426Y-177768D01*
X647334Y-176602D01*
X645806Y-176019D01*
X644277Y-176310D01*
X642967Y-177185D01*
X642094Y-179227D01*
X641657Y-180977D01*
Y-182727D01*
X642094Y-184477D01*
X643186Y-186227D01*
X644496Y-187393D01*
X646024Y-187685D01*
X647552Y-187102D01*
X649081Y-185352D01*
G01X659594Y-185644D02*
X660686Y-186810D01*
X662214Y-187685D01*
X663524D01*
X664834Y-187102D01*
X665707Y-186227D01*
X666144Y-185061D01*
X665926Y-183310D01*
X665052Y-182435D01*
X661122Y-180685D01*
X660249Y-178643D01*
X660686Y-177185D01*
X661559Y-176310D01*
X662869Y-176019D01*
X664179Y-176310D01*
X665489Y-177185D01*
G01X680369Y-176019D02*
Y-187685D01*
G01Y-171352D02*
X679932Y-171060D01*
Y-170477D01*
X680369Y-170185D01*
X680806Y-170477D01*
Y-171060D01*
X680369Y-171352D01*
G01X694812Y-192060D02*
X696341Y-193227D01*
X698087Y-193518D01*
X699615Y-193227D01*
X700926Y-191769D01*
X701799Y-189727D01*
Y-176019D01*
G01Y-178352D02*
X700926Y-177185D01*
X699615Y-176310D01*
X698087Y-176019D01*
X696341Y-176602D01*
X695249Y-177768D01*
X694375Y-179810D01*
X693939Y-181852D01*
X694157Y-183602D01*
X695031Y-185644D01*
X696341Y-187102D01*
X698087Y-187685D01*
X699397Y-187393D01*
X700926Y-186227D01*
X701799Y-185061D01*
G01X711657Y-187685D02*
Y-176019D01*
G01Y-178935D02*
X712531Y-177477D01*
X713841Y-176310D01*
X715587Y-176019D01*
X717115Y-176310D01*
X718426Y-177477D01*
X719081Y-179518D01*
Y-187685D01*
G01X729594Y-179810D02*
X736581D01*
X735926Y-177768D01*
X734834Y-176602D01*
X733306Y-176019D01*
X731777Y-176310D01*
X730467Y-177185D01*
X729594Y-179227D01*
X729157Y-180977D01*
Y-182727D01*
X729594Y-184477D01*
X730686Y-186227D01*
X731996Y-187393D01*
X733524Y-187685D01*
X735052Y-187102D01*
X736581Y-185352D01*
G01X747312Y-187685D02*
Y-176019D01*
G01Y-178352D02*
X748404Y-177185D01*
X749496Y-176310D01*
X751024Y-176019D01*
X752115Y-176310D01*
X753426Y-177185D01*
G01X624436Y672196D02*
Y684696D01*
X630326D01*
G01X628156Y678654D02*
X624436D01*
G01X637921Y684696D02*
X641641D01*
G01X639781D02*
Y672196D01*
G01X637921D02*
X641641D01*
G01X653111Y678446D02*
X656211D01*
Y674696D01*
X655281Y673446D01*
X654196Y672613D01*
X652646Y672196D01*
X651096Y672613D01*
X650011Y673446D01*
X649081Y674696D01*
X648461Y676154D01*
X648151Y677821D01*
Y679279D01*
X648461Y680529D01*
X649081Y681988D01*
X650011Y683238D01*
X650941Y684071D01*
X652181Y684696D01*
X653266D01*
X654506Y684279D01*
X655436Y683446D01*
G01X661171Y684696D02*
Y675738D01*
X661791Y673862D01*
X663031Y672613D01*
X664581Y672196D01*
X666131Y672613D01*
X667371Y673862D01*
X667991Y675738D01*
Y684696D01*
G01X673881Y672196D02*
Y684696D01*
X677756D01*
X678996Y684071D01*
X679771Y683238D01*
X680081Y681571D01*
X679771Y679904D01*
X678841Y678863D01*
X677756Y678238D01*
X673881D01*
G01X677756D02*
X680081Y672196D01*
G01X692481D02*
X686281D01*
Y684696D01*
X692481D01*
G01X690001Y678654D02*
X686281D01*
G01X664179Y-223935D02*
X668546D01*
Y-229185D01*
X667236Y-230935D01*
X665707Y-232102D01*
X663524Y-232685D01*
X661341Y-232102D01*
X659812Y-230935D01*
X658502Y-229185D01*
X657629Y-227143D01*
X657192Y-224810D01*
Y-222768D01*
X657629Y-221019D01*
X658502Y-218976D01*
X659812Y-217227D01*
X661122Y-216060D01*
X662869Y-215185D01*
X664397D01*
X666144Y-215768D01*
X667454Y-216935D01*
G01X684736Y-232685D02*
X676002D01*
Y-215185D01*
X684736D01*
G01X681242Y-223643D02*
X676002D01*
G01X693502Y-215185D02*
Y-232685D01*
X702236D01*
G01X715369D02*
X713622Y-232393D01*
X712094Y-231227D01*
X710784Y-229477D01*
X709910Y-227435D01*
X709474Y-225102D01*
Y-222768D01*
X709910Y-220435D01*
X710784Y-218393D01*
X712094Y-216644D01*
X713622Y-215477D01*
X715369Y-215185D01*
X717115Y-215477D01*
X718644Y-216644D01*
X719954Y-218393D01*
X720828Y-220435D01*
X721264Y-222768D01*
Y-225102D01*
X720828Y-227435D01*
X719954Y-229477D01*
X718644Y-231227D01*
X717115Y-232393D01*
X715369Y-232685D01*
G01X703331Y690946D02*
Y340946D01*
G01X696821Y722196D02*
Y734696D01*
X699921D01*
X701161Y734071D01*
X702091Y733238D01*
X702866Y731988D01*
X703486Y730529D01*
X703641Y728446D01*
X703486Y726363D01*
X702866Y724904D01*
X702091Y723654D01*
X701161Y722821D01*
X699921Y722196D01*
X696821D01*
G01X709531D02*
Y734696D01*
X713406D01*
X714646Y734071D01*
X715421Y733238D01*
X715731Y731571D01*
X715421Y729904D01*
X714491Y728863D01*
X713406Y728238D01*
X709531D01*
G01X713406D02*
X715731Y722196D01*
G01X723171Y734696D02*
X726891D01*
G01X725031D02*
Y722196D01*
G01X723171D02*
X726891D01*
G01X734331Y734696D02*
Y722196D01*
X740531D01*
G01X746731Y734696D02*
Y722196D01*
X752931D01*
G01X778041Y733654D02*
X777111Y734279D01*
X776026Y734696D01*
X774786D01*
X773391Y734071D01*
X772306Y733029D01*
X771531Y731779D01*
X770911Y729696D01*
X770756Y727821D01*
X771066Y725946D01*
X771531Y724696D01*
X772461Y723446D01*
X773546Y722613D01*
X774631Y722196D01*
X775716D01*
X776801Y722613D01*
X777731Y723237D01*
X778506Y724071D01*
G01X783776Y722196D02*
Y734696D01*
G01X790286D02*
Y722196D01*
G01Y728446D02*
X783776D01*
G01X795556Y722196D02*
X799431Y734696D01*
X803306Y722196D01*
G01X801911Y726571D02*
X796951D01*
G01X808731Y722196D02*
Y734696D01*
X812606D01*
X813846Y734071D01*
X814621Y733238D01*
X814931Y731571D01*
X814621Y729904D01*
X813691Y728863D01*
X812606Y728238D01*
X808731D01*
G01X812606D02*
X814931Y722196D01*
G01X824231Y734696D02*
Y722196D01*
G01X820666Y734696D02*
X827796D01*
G01X836631Y721779D02*
X836321Y721988D01*
Y722404D01*
X836631Y722613D01*
X836941Y722404D01*
Y721988D01*
X836631Y721779D01*
G01Y727404D02*
X836321Y727613D01*
Y728029D01*
X836631Y728238D01*
X836941Y728029D01*
Y727613D01*
X836631Y727404D01*
G01X861431Y734696D02*
Y722196D01*
G01X857866Y734696D02*
X864996D01*
G01X873831Y722196D02*
X872591Y722404D01*
X871506Y723237D01*
X870576Y724488D01*
X869956Y725946D01*
X869646Y727613D01*
Y729279D01*
X869956Y730946D01*
X870576Y732404D01*
X871506Y733654D01*
X872591Y734488D01*
X873831Y734696D01*
X875071Y734488D01*
X876156Y733654D01*
X877086Y732404D01*
X877706Y730946D01*
X878016Y729279D01*
Y727613D01*
X877706Y725946D01*
X877086Y724488D01*
X876156Y723237D01*
X875071Y722404D01*
X873831Y722196D01*
G01X883131D02*
Y734696D01*
X886851D01*
X888091Y734071D01*
X889021Y732613D01*
X889331Y730946D01*
X889021Y729279D01*
X888246Y728029D01*
X886851Y727404D01*
X883131D01*
G01X911031Y734696D02*
Y722196D01*
G01X908861Y730529D02*
X913201D01*
G01X923431Y722196D02*
X922501Y722404D01*
X921571Y723237D01*
X920951Y724696D01*
X920641Y726363D01*
X920951Y728029D01*
X921571Y729488D01*
X922501Y730321D01*
X923431Y730529D01*
X924361Y730321D01*
X925291Y729488D01*
X925911Y728029D01*
X926066Y726363D01*
X925911Y724696D01*
X925291Y723237D01*
X924361Y722404D01*
X923431Y722196D01*
G01X949471Y728863D02*
X950091Y729488D01*
X950556Y730529D01*
X950866Y731988D01*
X950556Y733238D01*
X949936Y734071D01*
X948851Y734696D01*
X944666D01*
Y722196D01*
X949781D01*
X950866Y723029D01*
X951486Y724279D01*
X951796Y725738D01*
X951486Y727196D01*
X950556Y728446D01*
X949471Y728863D01*
X944666D01*
G01X960631Y722196D02*
X959391Y722404D01*
X958306Y723237D01*
X957376Y724488D01*
X956756Y725946D01*
X956446Y727613D01*
Y729279D01*
X956756Y730946D01*
X957376Y732404D01*
X958306Y733654D01*
X959391Y734488D01*
X960631Y734696D01*
X961871Y734488D01*
X962956Y733654D01*
X963886Y732404D01*
X964506Y730946D01*
X964816Y729279D01*
Y727613D01*
X964506Y725946D01*
X963886Y724488D01*
X962956Y723237D01*
X961871Y722404D01*
X960631Y722196D01*
G01X973031Y734696D02*
Y722196D01*
G01X969466Y734696D02*
X976596D01*
G01X985431D02*
Y722196D01*
G01X981866Y734696D02*
X988996D01*
G01X997831Y722196D02*
X996591Y722404D01*
X995506Y723237D01*
X994576Y724488D01*
X993956Y725946D01*
X993646Y727613D01*
Y729279D01*
X993956Y730946D01*
X994576Y732404D01*
X995506Y733654D01*
X996591Y734488D01*
X997831Y734696D01*
X999071Y734488D01*
X1000156Y733654D01*
X1001086Y732404D01*
X1001706Y730946D01*
X1002016Y729279D01*
Y727613D01*
X1001706Y725946D01*
X1001086Y724488D01*
X1000156Y723237D01*
X999071Y722404D01*
X997831Y722196D01*
G01X1006201D02*
Y734696D01*
X1010231Y724279D01*
X1014261Y734696D01*
Y722196D01*
G01X727356Y697196D02*
X731231Y709696D01*
X735106Y697196D01*
G01X733711Y701571D02*
X728751D01*
G01X740531Y709696D02*
Y697196D01*
X746731D01*
G01X752931Y709696D02*
Y697196D01*
X759131D01*
G01X777421Y709696D02*
Y700738D01*
X778041Y698862D01*
X779281Y697613D01*
X780831Y697196D01*
X782381Y697613D01*
X783621Y698862D01*
X784241Y700738D01*
Y709696D01*
G01X789666Y697196D02*
Y709696D01*
X796796Y697196D01*
Y709696D01*
G01X803771D02*
X807491D01*
G01X805631D02*
Y697196D01*
G01X803771D02*
X807491D01*
G01X818031Y709696D02*
Y697196D01*
G01X814466Y709696D02*
X821596D01*
G01X827176Y698862D02*
X828416Y697821D01*
X829811Y697196D01*
X831051D01*
X832291Y697821D01*
X833221Y698862D01*
X833686Y700321D01*
X833376Y701779D01*
X832601Y703029D01*
X831206Y703863D01*
X829346Y704279D01*
X828261Y705113D01*
X827796Y706571D01*
X828106Y708029D01*
X828881Y709071D01*
X829966Y709696D01*
X831051D01*
X832136Y709279D01*
X833066Y708238D01*
G01X851356Y697196D02*
X855231Y709696D01*
X859106Y697196D01*
G01X857711Y701571D02*
X852751D01*
G01X864531Y697196D02*
Y709696D01*
X868406D01*
X869646Y709071D01*
X870421Y708238D01*
X870731Y706571D01*
X870421Y704904D01*
X869491Y703863D01*
X868406Y703238D01*
X864531D01*
G01X868406D02*
X870731Y697196D01*
G01X883131D02*
X876931D01*
Y709696D01*
X883131D01*
G01X880651Y703654D02*
X876931D01*
G01X902971Y709696D02*
X906691D01*
G01X904831D02*
Y697196D01*
G01X902971D02*
X906691D01*
G01X913666D02*
Y709696D01*
X920796Y697196D01*
Y709696D01*
G01X938001Y697196D02*
Y709696D01*
X942031Y699279D01*
X946061Y709696D01*
Y697196D01*
G01X952571Y709696D02*
X956291D01*
G01X954431D02*
Y697196D01*
G01X952571D02*
X956291D01*
G01X963731Y709696D02*
Y697196D01*
X969931D01*
G01X975976Y698862D02*
X977216Y697821D01*
X978611Y697196D01*
X979851D01*
X981091Y697821D01*
X982021Y698862D01*
X982486Y700321D01*
X982176Y701779D01*
X981401Y703029D01*
X980006Y703863D01*
X978146Y704279D01*
X977061Y705113D01*
X976596Y706571D01*
X976906Y708029D01*
X977681Y709071D01*
X978766Y709696D01*
X979851D01*
X980936Y709279D01*
X981866Y708238D01*
G01X744871Y349071D02*
X745801Y348029D01*
X746886Y347404D01*
X748281Y347196D01*
X749676Y347613D01*
X750761Y348446D01*
X751536Y349904D01*
X751691Y351571D01*
X751381Y353238D01*
X750606Y354279D01*
X749521Y355113D01*
X748436Y355321D01*
X747351Y355113D01*
X745956Y354279D01*
X746421Y359696D01*
X750606D01*
G01X760681Y347196D02*
X761766Y347404D01*
X763006Y348029D01*
X763781Y349071D01*
X764091Y350529D01*
X763781Y351987D01*
X762851Y353238D01*
X761456Y353863D01*
X759906D01*
X758976Y354279D01*
X758201Y355321D01*
X757891Y356779D01*
X758356Y358238D01*
X759441Y359279D01*
X760681Y359696D01*
X761921Y359279D01*
X763006Y358238D01*
X763471Y356779D01*
X763161Y355321D01*
X762386Y354279D01*
X761456Y353863D01*
X759906D01*
X758511Y353238D01*
X757581Y351987D01*
X757271Y350529D01*
X757581Y349071D01*
X758356Y348029D01*
X759596Y347404D01*
X760681Y347196D01*
G01X773081Y346779D02*
X772771Y346988D01*
Y347404D01*
X773081Y347613D01*
X773391Y347404D01*
Y346988D01*
X773081Y346779D01*
G01X785481Y359696D02*
X784241Y359279D01*
X783311Y358238D01*
X782691Y356988D01*
X782226Y355321D01*
X782071Y353446D01*
X782226Y351571D01*
X782691Y349904D01*
X783311Y348654D01*
X784241Y347613D01*
X785481Y347196D01*
X786721Y347613D01*
X787651Y348654D01*
X788271Y349904D01*
X788736Y351571D01*
X788891Y353446D01*
X788736Y355321D01*
X788271Y356988D01*
X787651Y358238D01*
X786721Y359279D01*
X785481Y359696D01*
G01X795556Y355529D02*
X800206Y347196D01*
G01Y355529D02*
X795556Y347196D01*
G01X807336Y357613D02*
X808266Y358862D01*
X809351Y359488D01*
X810591Y359696D01*
X812141Y359279D01*
X813226Y358238D01*
X813536Y356988D01*
X813381Y355737D01*
X812761Y354696D01*
X809661Y352613D01*
X808266Y351154D01*
X807336Y349071D01*
X807026Y347196D01*
X813536D01*
G01X822681Y359696D02*
X821441Y359279D01*
X820511Y358238D01*
X819891Y356988D01*
X819426Y355321D01*
X819271Y353446D01*
X819426Y351571D01*
X819891Y349904D01*
X820511Y348654D01*
X821441Y347613D01*
X822681Y347196D01*
X823921Y347613D01*
X824851Y348654D01*
X825471Y349904D01*
X825936Y351571D01*
X826091Y353446D01*
X825936Y355321D01*
X825471Y356988D01*
X824851Y358238D01*
X823921Y359279D01*
X822681Y359696D01*
G01X835081Y346779D02*
X834771Y346988D01*
Y347404D01*
X835081Y347613D01*
X835391Y347404D01*
Y346988D01*
X835081Y346779D01*
G01X847481Y359696D02*
X846241Y359279D01*
X845311Y358238D01*
X844691Y356988D01*
X844226Y355321D01*
X844071Y353446D01*
X844226Y351571D01*
X844691Y349904D01*
X845311Y348654D01*
X846241Y347613D01*
X847481Y347196D01*
X848721Y347613D01*
X849651Y348654D01*
X850271Y349904D01*
X850736Y351571D01*
X850891Y353446D01*
X850736Y355321D01*
X850271Y356988D01*
X849651Y358238D01*
X848721Y359279D01*
X847481Y359696D01*
G01X779281Y372196D02*
X780366Y372404D01*
X781606Y373029D01*
X782381Y374071D01*
X782691Y375529D01*
X782381Y376987D01*
X781451Y378238D01*
X780056Y378863D01*
X778506D01*
X777576Y379279D01*
X776801Y380321D01*
X776491Y381779D01*
X776956Y383238D01*
X778041Y384279D01*
X779281Y384696D01*
X780521Y384279D01*
X781606Y383238D01*
X782071Y381779D01*
X781761Y380321D01*
X780986Y379279D01*
X780056Y378863D01*
X778506D01*
X777111Y378238D01*
X776181Y376987D01*
X775871Y375529D01*
X776181Y374071D01*
X776956Y373029D01*
X778196Y372404D01*
X779281Y372196D01*
G01X788736Y377404D02*
X789821Y378863D01*
X790751Y379696D01*
X791991Y380113D01*
X793076Y379696D01*
X793851Y378863D01*
X794471Y377613D01*
X794626Y376154D01*
X794471Y374904D01*
X793851Y373654D01*
X792921Y372613D01*
X791836Y372196D01*
X790596Y372613D01*
X789511Y373862D01*
X788891Y375738D01*
X788736Y377821D01*
X789046Y380529D01*
X789511Y381988D01*
X790286Y383446D01*
X791371Y384488D01*
X792456Y384696D01*
X793541Y384279D01*
X794316Y383238D01*
G01X804081Y371779D02*
X803771Y371988D01*
Y372404D01*
X804081Y372613D01*
X804391Y372404D01*
Y371988D01*
X804081Y371779D01*
G01X816481Y384696D02*
X815241Y384279D01*
X814311Y383238D01*
X813691Y381988D01*
X813226Y380321D01*
X813071Y378446D01*
X813226Y376571D01*
X813691Y374904D01*
X814311Y373654D01*
X815241Y372613D01*
X816481Y372196D01*
X817721Y372613D01*
X818651Y373654D01*
X819271Y374904D01*
X819736Y376571D01*
X819891Y378446D01*
X819736Y380321D01*
X819271Y381988D01*
X818651Y383238D01*
X817721Y384279D01*
X816481Y384696D01*
G01X775871Y399071D02*
X776801Y398029D01*
X777886Y397404D01*
X779281Y397196D01*
X780676Y397613D01*
X781761Y398446D01*
X782536Y399904D01*
X782691Y401571D01*
X782381Y403238D01*
X781606Y404279D01*
X780521Y405113D01*
X779436Y405321D01*
X778351Y405113D01*
X776956Y404279D01*
X777421Y409696D01*
X781606D01*
G01X788271Y399696D02*
X789201Y398237D01*
X790441Y397404D01*
X791836Y397196D01*
X793076Y397404D01*
X794316Y398446D01*
X795091Y399696D01*
X795246Y400946D01*
X794936Y402404D01*
X793851Y403446D01*
X792766Y403863D01*
X791371D01*
G01X792766D02*
X793696Y404488D01*
X794471Y405529D01*
X794781Y406779D01*
X794471Y408029D01*
X793696Y409071D01*
X792301Y409696D01*
X790906Y409488D01*
X789511Y408654D01*
G01X804081Y396779D02*
X803771Y396988D01*
Y397404D01*
X804081Y397613D01*
X804391Y397404D01*
Y396988D01*
X804081Y396779D01*
G01X816481Y409696D02*
X815241Y409279D01*
X814311Y408238D01*
X813691Y406988D01*
X813226Y405321D01*
X813071Y403446D01*
X813226Y401571D01*
X813691Y399904D01*
X814311Y398654D01*
X815241Y397613D01*
X816481Y397196D01*
X817721Y397613D01*
X818651Y398654D01*
X819271Y399904D01*
X819736Y401571D01*
X819891Y403446D01*
X819736Y405321D01*
X819271Y406988D01*
X818651Y408238D01*
X817721Y409279D01*
X816481Y409696D01*
G01X775871Y424071D02*
X776801Y423029D01*
X777886Y422404D01*
X779281Y422196D01*
X780676Y422613D01*
X781761Y423446D01*
X782536Y424904D01*
X782691Y426571D01*
X782381Y428238D01*
X781606Y429279D01*
X780521Y430113D01*
X779436Y430321D01*
X778351Y430113D01*
X776956Y429279D01*
X777421Y434696D01*
X781606D01*
G01X791681D02*
X790441Y434279D01*
X789511Y433238D01*
X788891Y431988D01*
X788426Y430321D01*
X788271Y428446D01*
X788426Y426571D01*
X788891Y424904D01*
X789511Y423654D01*
X790441Y422613D01*
X791681Y422196D01*
X792921Y422613D01*
X793851Y423654D01*
X794471Y424904D01*
X794936Y426571D01*
X795091Y428446D01*
X794936Y430321D01*
X794471Y431988D01*
X793851Y433238D01*
X792921Y434279D01*
X791681Y434696D01*
G01X804081Y421779D02*
X803771Y421988D01*
Y422404D01*
X804081Y422613D01*
X804391Y422404D01*
Y421988D01*
X804081Y421779D01*
G01X816481Y434696D02*
X815241Y434279D01*
X814311Y433238D01*
X813691Y431988D01*
X813226Y430321D01*
X813071Y428446D01*
X813226Y426571D01*
X813691Y424904D01*
X814311Y423654D01*
X815241Y422613D01*
X816481Y422196D01*
X817721Y422613D01*
X818651Y423654D01*
X819271Y424904D01*
X819736Y426571D01*
X819891Y428446D01*
X819736Y430321D01*
X819271Y431988D01*
X818651Y433238D01*
X817721Y434279D01*
X816481Y434696D01*
G01X781141Y447196D02*
Y459696D01*
X775406Y450738D01*
X783156D01*
G01X791681Y447196D02*
X792766Y447404D01*
X794006Y448029D01*
X794781Y449071D01*
X795091Y450529D01*
X794781Y451987D01*
X793851Y453238D01*
X792456Y453863D01*
X790906D01*
X789976Y454279D01*
X789201Y455321D01*
X788891Y456779D01*
X789356Y458238D01*
X790441Y459279D01*
X791681Y459696D01*
X792921Y459279D01*
X794006Y458238D01*
X794471Y456779D01*
X794161Y455321D01*
X793386Y454279D01*
X792456Y453863D01*
X790906D01*
X789511Y453238D01*
X788581Y451987D01*
X788271Y450529D01*
X788581Y449071D01*
X789356Y448029D01*
X790596Y447404D01*
X791681Y447196D01*
G01X804081Y446779D02*
X803771Y446988D01*
Y447404D01*
X804081Y447613D01*
X804391Y447404D01*
Y446988D01*
X804081Y446779D01*
G01X816481Y459696D02*
X815241Y459279D01*
X814311Y458238D01*
X813691Y456988D01*
X813226Y455321D01*
X813071Y453446D01*
X813226Y451571D01*
X813691Y449904D01*
X814311Y448654D01*
X815241Y447613D01*
X816481Y447196D01*
X817721Y447613D01*
X818651Y448654D01*
X819271Y449904D01*
X819736Y451571D01*
X819891Y453446D01*
X819736Y455321D01*
X819271Y456988D01*
X818651Y458238D01*
X817721Y459279D01*
X816481Y459696D01*
G01X773081Y472196D02*
Y484696D01*
X771221Y482196D01*
G01Y472196D02*
X774941D01*
G01X782536Y477404D02*
X783621Y478863D01*
X784551Y479696D01*
X785791Y480113D01*
X786876Y479696D01*
X787651Y478863D01*
X788271Y477613D01*
X788426Y476154D01*
X788271Y474904D01*
X787651Y473654D01*
X786721Y472613D01*
X785636Y472196D01*
X784396Y472613D01*
X783311Y473862D01*
X782691Y475738D01*
X782536Y477821D01*
X782846Y480529D01*
X783311Y481988D01*
X784086Y483446D01*
X785171Y484488D01*
X786256Y484696D01*
X787341Y484279D01*
X788116Y483238D01*
G01X794936Y477404D02*
X796021Y478863D01*
X796951Y479696D01*
X798191Y480113D01*
X799276Y479696D01*
X800051Y478863D01*
X800671Y477613D01*
X800826Y476154D01*
X800671Y474904D01*
X800051Y473654D01*
X799121Y472613D01*
X798036Y472196D01*
X796796Y472613D01*
X795711Y473862D01*
X795091Y475738D01*
X794936Y477821D01*
X795246Y480529D01*
X795711Y481988D01*
X796486Y483446D01*
X797571Y484488D01*
X798656Y484696D01*
X799741Y484279D01*
X800516Y483238D01*
G01X810281Y471779D02*
X809971Y471988D01*
Y472404D01*
X810281Y472613D01*
X810591Y472404D01*
Y471988D01*
X810281Y471779D01*
G01X822681Y484696D02*
X821441Y484279D01*
X820511Y483238D01*
X819891Y481988D01*
X819426Y480321D01*
X819271Y478446D01*
X819426Y476571D01*
X819891Y474904D01*
X820511Y473654D01*
X821441Y472613D01*
X822681Y472196D01*
X823921Y472613D01*
X824851Y473654D01*
X825471Y474904D01*
X825936Y476571D01*
X826091Y478446D01*
X825936Y480321D01*
X825471Y481988D01*
X824851Y483238D01*
X823921Y484279D01*
X822681Y484696D01*
G01X773081Y497196D02*
Y509696D01*
X771221Y507196D01*
G01Y497196D02*
X774941D01*
G01X782071Y499696D02*
X783001Y498237D01*
X784241Y497404D01*
X785636Y497196D01*
X786876Y497404D01*
X788116Y498446D01*
X788891Y499696D01*
X789046Y500946D01*
X788736Y502404D01*
X787651Y503446D01*
X786566Y503863D01*
X785171D01*
G01X786566D02*
X787496Y504488D01*
X788271Y505529D01*
X788581Y506779D01*
X788271Y508029D01*
X787496Y509071D01*
X786101Y509696D01*
X784706Y509488D01*
X783311Y508654D01*
G01X797881Y509696D02*
X796641Y509279D01*
X795711Y508238D01*
X795091Y506988D01*
X794626Y505321D01*
X794471Y503446D01*
X794626Y501571D01*
X795091Y499904D01*
X795711Y498654D01*
X796641Y497613D01*
X797881Y497196D01*
X799121Y497613D01*
X800051Y498654D01*
X800671Y499904D01*
X801136Y501571D01*
X801291Y503446D01*
X801136Y505321D01*
X800671Y506988D01*
X800051Y508238D01*
X799121Y509279D01*
X797881Y509696D01*
G01X810281Y496779D02*
X809971Y496988D01*
Y497404D01*
X810281Y497613D01*
X810591Y497404D01*
Y496988D01*
X810281Y496779D01*
G01X822681Y509696D02*
X821441Y509279D01*
X820511Y508238D01*
X819891Y506988D01*
X819426Y505321D01*
X819271Y503446D01*
X819426Y501571D01*
X819891Y499904D01*
X820511Y498654D01*
X821441Y497613D01*
X822681Y497196D01*
X823921Y497613D01*
X824851Y498654D01*
X825471Y499904D01*
X825936Y501571D01*
X826091Y503446D01*
X825936Y505321D01*
X825471Y506988D01*
X824851Y508238D01*
X823921Y509279D01*
X822681Y509696D01*
G01X772771Y522196D02*
X773081Y524904D01*
X773546Y527196D01*
X774166Y529279D01*
X774941Y531571D01*
X776181Y534696D01*
X769981D01*
G01X782536Y527404D02*
X783621Y528863D01*
X784551Y529696D01*
X785791Y530113D01*
X786876Y529696D01*
X787651Y528863D01*
X788271Y527613D01*
X788426Y526154D01*
X788271Y524904D01*
X787651Y523654D01*
X786721Y522613D01*
X785636Y522196D01*
X784396Y522613D01*
X783311Y523862D01*
X782691Y525738D01*
X782536Y527821D01*
X782846Y530529D01*
X783311Y531988D01*
X784086Y533446D01*
X785171Y534488D01*
X786256Y534696D01*
X787341Y534279D01*
X788116Y533238D01*
G01X797881Y521779D02*
X797571Y521988D01*
Y522404D01*
X797881Y522613D01*
X798191Y522404D01*
Y521988D01*
X797881Y521779D01*
G01X809971Y522196D02*
X810281Y524904D01*
X810746Y527196D01*
X811366Y529279D01*
X812141Y531571D01*
X813381Y534696D01*
X807181D01*
G01X822371Y522196D02*
X822681Y524904D01*
X823146Y527196D01*
X823766Y529279D01*
X824541Y531571D01*
X825781Y534696D01*
X819581D01*
G01X781141Y547196D02*
Y559696D01*
X775406Y550738D01*
X783156D01*
G01X788736Y552404D02*
X789821Y553863D01*
X790751Y554696D01*
X791991Y555113D01*
X793076Y554696D01*
X793851Y553863D01*
X794471Y552613D01*
X794626Y551154D01*
X794471Y549904D01*
X793851Y548654D01*
X792921Y547613D01*
X791836Y547196D01*
X790596Y547613D01*
X789511Y548862D01*
X788891Y550738D01*
X788736Y552821D01*
X789046Y555529D01*
X789511Y556988D01*
X790286Y558446D01*
X791371Y559488D01*
X792456Y559696D01*
X793541Y559279D01*
X794316Y558238D01*
G01X804081Y546779D02*
X803771Y546988D01*
Y547404D01*
X804081Y547613D01*
X804391Y547404D01*
Y546988D01*
X804081Y546779D01*
G01X816481Y559696D02*
X815241Y559279D01*
X814311Y558238D01*
X813691Y556988D01*
X813226Y555321D01*
X813071Y553446D01*
X813226Y551571D01*
X813691Y549904D01*
X814311Y548654D01*
X815241Y547613D01*
X816481Y547196D01*
X817721Y547613D01*
X818651Y548654D01*
X819271Y549904D01*
X819736Y551571D01*
X819891Y553446D01*
X819736Y555321D01*
X819271Y556988D01*
X818651Y558238D01*
X817721Y559279D01*
X816481Y559696D01*
G01X773081Y572196D02*
Y584696D01*
X771221Y582196D01*
G01Y572196D02*
X774941D01*
G01X782846Y573654D02*
X783931Y572613D01*
X785171Y572196D01*
X786411Y572613D01*
X787496Y573862D01*
X788271Y575738D01*
X788581Y577613D01*
Y579904D01*
X788271Y581779D01*
X787496Y583446D01*
X786566Y584279D01*
X785481Y584696D01*
X784241Y584279D01*
X783311Y583446D01*
X782691Y582196D01*
X782381Y580529D01*
X782691Y579071D01*
X783466Y577613D01*
X784396Y576779D01*
X785481Y576571D01*
X786721Y576987D01*
X787651Y578029D01*
X788581Y579904D01*
G01X797881Y571779D02*
X797571Y571988D01*
Y572404D01*
X797881Y572613D01*
X798191Y572404D01*
Y571988D01*
X797881Y571779D01*
G01X807336Y577404D02*
X808421Y578863D01*
X809351Y579696D01*
X810591Y580113D01*
X811676Y579696D01*
X812451Y578863D01*
X813071Y577613D01*
X813226Y576154D01*
X813071Y574904D01*
X812451Y573654D01*
X811521Y572613D01*
X810436Y572196D01*
X809196Y572613D01*
X808111Y573862D01*
X807491Y575738D01*
X807336Y577821D01*
X807646Y580529D01*
X808111Y581988D01*
X808886Y583446D01*
X809971Y584488D01*
X811056Y584696D01*
X812141Y584279D01*
X812916Y583238D01*
G01X822681Y572196D02*
X823766Y572404D01*
X825006Y573029D01*
X825781Y574071D01*
X826091Y575529D01*
X825781Y576987D01*
X824851Y578238D01*
X823456Y578863D01*
X821906D01*
X820976Y579279D01*
X820201Y580321D01*
X819891Y581779D01*
X820356Y583238D01*
X821441Y584279D01*
X822681Y584696D01*
X823921Y584279D01*
X825006Y583238D01*
X825471Y581779D01*
X825161Y580321D01*
X824386Y579279D01*
X823456Y578863D01*
X821906D01*
X820511Y578238D01*
X819581Y576987D01*
X819271Y575529D01*
X819581Y574071D01*
X820356Y573029D01*
X821596Y572404D01*
X822681Y572196D01*
G01X773081Y597196D02*
Y609696D01*
X771221Y607196D01*
G01Y597196D02*
X774941D01*
G01X782071Y599071D02*
X783001Y598029D01*
X784086Y597404D01*
X785481Y597196D01*
X786876Y597613D01*
X787961Y598446D01*
X788736Y599904D01*
X788891Y601571D01*
X788581Y603238D01*
X787806Y604279D01*
X786721Y605113D01*
X785636Y605321D01*
X784551Y605113D01*
X783156Y604279D01*
X783621Y609696D01*
X787806D01*
G01X797881Y596779D02*
X797571Y596988D01*
Y597404D01*
X797881Y597613D01*
X798191Y597404D01*
Y596988D01*
X797881Y596779D01*
G01X809971Y597196D02*
X810281Y599904D01*
X810746Y602196D01*
X811366Y604279D01*
X812141Y606571D01*
X813381Y609696D01*
X807181D01*
G01X824541Y597196D02*
Y609696D01*
X818806Y600738D01*
X826556D01*
G01X779281Y622196D02*
Y634696D01*
X777421Y632196D01*
G01Y622196D02*
X781141D01*
G01X788736Y632613D02*
X789666Y633862D01*
X790751Y634488D01*
X791991Y634696D01*
X793541Y634279D01*
X794626Y633238D01*
X794936Y631988D01*
X794781Y630737D01*
X794161Y629696D01*
X791061Y627613D01*
X789666Y626154D01*
X788736Y624071D01*
X788426Y622196D01*
X794936D01*
G01X804081Y621779D02*
X803771Y621988D01*
Y622404D01*
X804081Y622613D01*
X804391Y622404D01*
Y621988D01*
X804081Y621779D01*
G01X816481Y634696D02*
X815241Y634279D01*
X814311Y633238D01*
X813691Y631988D01*
X813226Y630321D01*
X813071Y628446D01*
X813226Y626571D01*
X813691Y624904D01*
X814311Y623654D01*
X815241Y622613D01*
X816481Y622196D01*
X817721Y622613D01*
X818651Y623654D01*
X819271Y624904D01*
X819736Y626571D01*
X819891Y628446D01*
X819736Y630321D01*
X819271Y631988D01*
X818651Y633238D01*
X817721Y634279D01*
X816481Y634696D01*
G01X779281Y647196D02*
Y659696D01*
X777421Y657196D01*
G01Y647196D02*
X781141D01*
G01X791681Y659696D02*
X790441Y659279D01*
X789511Y658238D01*
X788891Y656988D01*
X788426Y655321D01*
X788271Y653446D01*
X788426Y651571D01*
X788891Y649904D01*
X789511Y648654D01*
X790441Y647613D01*
X791681Y647196D01*
X792921Y647613D01*
X793851Y648654D01*
X794471Y649904D01*
X794936Y651571D01*
X795091Y653446D01*
X794936Y655321D01*
X794471Y656988D01*
X793851Y658238D01*
X792921Y659279D01*
X791681Y659696D01*
G01X804081Y646779D02*
X803771Y646988D01*
Y647404D01*
X804081Y647613D01*
X804391Y647404D01*
Y646988D01*
X804081Y646779D01*
G01X816481Y659696D02*
X815241Y659279D01*
X814311Y658238D01*
X813691Y656988D01*
X813226Y655321D01*
X813071Y653446D01*
X813226Y651571D01*
X813691Y649904D01*
X814311Y648654D01*
X815241Y647613D01*
X816481Y647196D01*
X817721Y647613D01*
X818651Y648654D01*
X819271Y649904D01*
X819736Y651571D01*
X819891Y653446D01*
X819736Y655321D01*
X819271Y656988D01*
X818651Y658238D01*
X817721Y659279D01*
X816481Y659696D01*
G01X776026Y673862D02*
X777266Y672821D01*
X778661Y672196D01*
X779901D01*
X781141Y672821D01*
X782071Y673862D01*
X782536Y675321D01*
X782226Y676779D01*
X781451Y678029D01*
X780056Y678863D01*
X778196Y679279D01*
X777111Y680113D01*
X776646Y681571D01*
X776956Y683029D01*
X777731Y684071D01*
X778816Y684696D01*
X779901D01*
X780986Y684279D01*
X781916Y683238D01*
G01X789821Y684696D02*
X793541D01*
G01X791681D02*
Y672196D01*
G01X789821D02*
X793541D01*
G01X801136Y684696D02*
X807026D01*
X801136Y672196D01*
X807026D01*
G01X819581D02*
X813381D01*
Y684696D01*
X819581D01*
G01X817101Y678654D02*
X813381D01*
G01X794069Y-215185D02*
X792322Y-215768D01*
X791012Y-217227D01*
X790139Y-218976D01*
X789484Y-221310D01*
X789266Y-223935D01*
X789484Y-226560D01*
X790139Y-228894D01*
X791012Y-230644D01*
X792322Y-232102D01*
X794069Y-232685D01*
X795815Y-232102D01*
X797126Y-230644D01*
X797999Y-228894D01*
X798654Y-226560D01*
X798872Y-223935D01*
X798654Y-221310D01*
X797999Y-218976D01*
X797126Y-217227D01*
X795815Y-215768D01*
X794069Y-215185D01*
G01X807421Y-225394D02*
X808949Y-223352D01*
X810259Y-222185D01*
X812006Y-221602D01*
X813534Y-222185D01*
X814626Y-223352D01*
X815499Y-225102D01*
X815717Y-227143D01*
X815499Y-228894D01*
X814626Y-230644D01*
X813315Y-232102D01*
X811787Y-232685D01*
X810041Y-232102D01*
X808512Y-230352D01*
X807639Y-227727D01*
X807421Y-224810D01*
X807857Y-221019D01*
X808512Y-218976D01*
X809604Y-216935D01*
X811132Y-215477D01*
X812661Y-215185D01*
X814189Y-215768D01*
X815281Y-217227D01*
G01X825139Y-233268D02*
X832999Y-215185D01*
G01X842421Y-218102D02*
X843731Y-216352D01*
X845259Y-215477D01*
X847006Y-215185D01*
X849189Y-215768D01*
X850717Y-217227D01*
X851154Y-218976D01*
X850936Y-220727D01*
X850062Y-222185D01*
X845696Y-225102D01*
X843731Y-227143D01*
X842421Y-230061D01*
X841984Y-232685D01*
X851154D01*
G01X859921Y-218102D02*
X861231Y-216352D01*
X862759Y-215477D01*
X864506Y-215185D01*
X866689Y-215768D01*
X868217Y-217227D01*
X868654Y-218976D01*
X868436Y-220727D01*
X867562Y-222185D01*
X863196Y-225102D01*
X861231Y-227143D01*
X859921Y-230061D01*
X859484Y-232685D01*
X868654D01*
G01X877639Y-233268D02*
X885499Y-215185D01*
G01X894921Y-218102D02*
X896231Y-216352D01*
X897759Y-215477D01*
X899506Y-215185D01*
X901689Y-215768D01*
X903217Y-217227D01*
X903654Y-218976D01*
X903436Y-220727D01*
X902562Y-222185D01*
X898196Y-225102D01*
X896231Y-227143D01*
X894921Y-230061D01*
X894484Y-232685D01*
X903654D01*
G01X916569Y-215185D02*
X914822Y-215768D01*
X913512Y-217227D01*
X912639Y-218976D01*
X911984Y-221310D01*
X911766Y-223935D01*
X911984Y-226560D01*
X912639Y-228894D01*
X913512Y-230644D01*
X914822Y-232102D01*
X916569Y-232685D01*
X918315Y-232102D01*
X919626Y-230644D01*
X920499Y-228894D01*
X921154Y-226560D01*
X921372Y-223935D01*
X921154Y-221310D01*
X920499Y-218976D01*
X919626Y-217227D01*
X918315Y-215768D01*
X916569Y-215185D01*
G01X934069Y-232685D02*
Y-215185D01*
X931449Y-218685D01*
G01Y-232685D02*
X936689D01*
G01X951132D02*
X951569Y-228894D01*
X952224Y-225685D01*
X953097Y-222768D01*
X954189Y-219560D01*
X955936Y-215185D01*
X947202D01*
G01X841766Y-187685D02*
Y-170185D01*
X846132D01*
X847879Y-171060D01*
X849189Y-172227D01*
X850281Y-173976D01*
X851154Y-176019D01*
X851372Y-178935D01*
X851154Y-181852D01*
X850281Y-183894D01*
X849189Y-185644D01*
X847879Y-186810D01*
X846132Y-187685D01*
X841766D01*
G01X867999D02*
Y-176019D01*
G01Y-178060D02*
X867126Y-176894D01*
X865815Y-176310D01*
X864287Y-176019D01*
X862759Y-176602D01*
X861449Y-177768D01*
X860575Y-179518D01*
X860139Y-181852D01*
X860575Y-184185D01*
X861449Y-185935D01*
X862759Y-187102D01*
X864287Y-187685D01*
X865815Y-187393D01*
X867126Y-186519D01*
X867999Y-185352D01*
G01X881569Y-170185D02*
Y-187685D01*
G01X878512Y-176019D02*
X884626D01*
G01X895794Y-179810D02*
X902781D01*
X902126Y-177768D01*
X901034Y-176602D01*
X899506Y-176019D01*
X897977Y-176310D01*
X896667Y-177185D01*
X895794Y-179227D01*
X895357Y-180977D01*
Y-182727D01*
X895794Y-184477D01*
X896886Y-186227D01*
X898196Y-187393D01*
X899724Y-187685D01*
X901252Y-187102D01*
X902781Y-185352D01*
G01X892431Y690946D02*
Y340946D01*
G01X896616Y372196D02*
Y384696D01*
X903746Y372196D01*
Y384696D01*
G01X912581Y372196D02*
X911341Y372404D01*
X910256Y373237D01*
X909326Y374488D01*
X908706Y375946D01*
X908396Y377613D01*
Y379279D01*
X908706Y380946D01*
X909326Y382404D01*
X910256Y383654D01*
X911341Y384488D01*
X912581Y384696D01*
X913821Y384488D01*
X914906Y383654D01*
X915836Y382404D01*
X916456Y380946D01*
X916766Y379279D01*
Y377613D01*
X916456Y375946D01*
X915836Y374488D01*
X914906Y373237D01*
X913821Y372404D01*
X912581Y372196D01*
G01X921416D02*
Y384696D01*
X928546Y372196D01*
Y384696D01*
G01X935366Y376363D02*
X939396D01*
G01X946681Y372196D02*
Y384696D01*
X950401D01*
X951641Y384071D01*
X952571Y382613D01*
X952881Y380946D01*
X952571Y379279D01*
X951796Y378029D01*
X950401Y377404D01*
X946681D01*
G01X959081Y384696D02*
Y372196D01*
X965281D01*
G01X970706D02*
X974581Y384696D01*
X978456Y372196D01*
G01X977061Y376571D02*
X972101D01*
G01X986981Y384696D02*
Y372196D01*
G01X983416Y384696D02*
X990546D01*
G01X1002481Y372196D02*
X996281D01*
Y384696D01*
X1002481D01*
G01X1000001Y378654D02*
X996281D01*
G01X1008371Y372196D02*
Y384696D01*
X1011471D01*
X1012711Y384071D01*
X1013641Y383238D01*
X1014416Y381988D01*
X1015036Y380529D01*
X1015191Y378446D01*
X1015036Y376363D01*
X1014416Y374904D01*
X1013641Y373654D01*
X1012711Y372821D01*
X1011471Y372196D01*
X1008371D01*
G01X896616Y397196D02*
Y409696D01*
X903746Y397196D01*
Y409696D01*
G01X912581Y397196D02*
X911341Y397404D01*
X910256Y398237D01*
X909326Y399488D01*
X908706Y400946D01*
X908396Y402613D01*
Y404279D01*
X908706Y405946D01*
X909326Y407404D01*
X910256Y408654D01*
X911341Y409488D01*
X912581Y409696D01*
X913821Y409488D01*
X914906Y408654D01*
X915836Y407404D01*
X916456Y405946D01*
X916766Y404279D01*
Y402613D01*
X916456Y400946D01*
X915836Y399488D01*
X914906Y398237D01*
X913821Y397404D01*
X912581Y397196D01*
G01X921416D02*
Y409696D01*
X928546Y397196D01*
Y409696D01*
G01X935366Y401363D02*
X939396D01*
G01X946681Y397196D02*
Y409696D01*
X950401D01*
X951641Y409071D01*
X952571Y407613D01*
X952881Y405946D01*
X952571Y404279D01*
X951796Y403029D01*
X950401Y402404D01*
X946681D01*
G01X959081Y409696D02*
Y397196D01*
X965281D01*
G01X970706D02*
X974581Y409696D01*
X978456Y397196D01*
G01X977061Y401571D02*
X972101D01*
G01X986981Y409696D02*
Y397196D01*
G01X983416Y409696D02*
X990546D01*
G01X1002481Y397196D02*
X996281D01*
Y409696D01*
X1002481D01*
G01X1000001Y403654D02*
X996281D01*
G01X1008371Y397196D02*
Y409696D01*
X1011471D01*
X1012711Y409071D01*
X1013641Y408238D01*
X1014416Y406988D01*
X1015036Y405529D01*
X1015191Y403446D01*
X1015036Y401363D01*
X1014416Y399904D01*
X1013641Y398654D01*
X1012711Y397821D01*
X1011471Y397196D01*
X1008371D01*
G01X896616Y422196D02*
Y434696D01*
X903746Y422196D01*
Y434696D01*
G01X912581Y422196D02*
X911341Y422404D01*
X910256Y423237D01*
X909326Y424488D01*
X908706Y425946D01*
X908396Y427613D01*
Y429279D01*
X908706Y430946D01*
X909326Y432404D01*
X910256Y433654D01*
X911341Y434488D01*
X912581Y434696D01*
X913821Y434488D01*
X914906Y433654D01*
X915836Y432404D01*
X916456Y430946D01*
X916766Y429279D01*
Y427613D01*
X916456Y425946D01*
X915836Y424488D01*
X914906Y423237D01*
X913821Y422404D01*
X912581Y422196D01*
G01X921416D02*
Y434696D01*
X928546Y422196D01*
Y434696D01*
G01X935366Y426363D02*
X939396D01*
G01X946681Y422196D02*
Y434696D01*
X950401D01*
X951641Y434071D01*
X952571Y432613D01*
X952881Y430946D01*
X952571Y429279D01*
X951796Y428029D01*
X950401Y427404D01*
X946681D01*
G01X959081Y434696D02*
Y422196D01*
X965281D01*
G01X970706D02*
X974581Y434696D01*
X978456Y422196D01*
G01X977061Y426571D02*
X972101D01*
G01X986981Y434696D02*
Y422196D01*
G01X983416Y434696D02*
X990546D01*
G01X1002481Y422196D02*
X996281D01*
Y434696D01*
X1002481D01*
G01X1000001Y428654D02*
X996281D01*
G01X1008371Y422196D02*
Y434696D01*
X1011471D01*
X1012711Y434071D01*
X1013641Y433238D01*
X1014416Y431988D01*
X1015036Y430529D01*
X1015191Y428446D01*
X1015036Y426363D01*
X1014416Y424904D01*
X1013641Y423654D01*
X1012711Y422821D01*
X1011471Y422196D01*
X1008371D01*
G01X896616Y447196D02*
Y459696D01*
X903746Y447196D01*
Y459696D01*
G01X912581Y447196D02*
X911341Y447404D01*
X910256Y448237D01*
X909326Y449488D01*
X908706Y450946D01*
X908396Y452613D01*
Y454279D01*
X908706Y455946D01*
X909326Y457404D01*
X910256Y458654D01*
X911341Y459488D01*
X912581Y459696D01*
X913821Y459488D01*
X914906Y458654D01*
X915836Y457404D01*
X916456Y455946D01*
X916766Y454279D01*
Y452613D01*
X916456Y450946D01*
X915836Y449488D01*
X914906Y448237D01*
X913821Y447404D01*
X912581Y447196D01*
G01X921416D02*
Y459696D01*
X928546Y447196D01*
Y459696D01*
G01X935366Y451363D02*
X939396D01*
G01X946681Y447196D02*
Y459696D01*
X950401D01*
X951641Y459071D01*
X952571Y457613D01*
X952881Y455946D01*
X952571Y454279D01*
X951796Y453029D01*
X950401Y452404D01*
X946681D01*
G01X959081Y459696D02*
Y447196D01*
X965281D01*
G01X970706D02*
X974581Y459696D01*
X978456Y447196D01*
G01X977061Y451571D02*
X972101D01*
G01X986981Y459696D02*
Y447196D01*
G01X983416Y459696D02*
X990546D01*
G01X1002481Y447196D02*
X996281D01*
Y459696D01*
X1002481D01*
G01X1000001Y453654D02*
X996281D01*
G01X1008371Y447196D02*
Y459696D01*
X1011471D01*
X1012711Y459071D01*
X1013641Y458238D01*
X1014416Y456988D01*
X1015036Y455529D01*
X1015191Y453446D01*
X1015036Y451363D01*
X1014416Y449904D01*
X1013641Y448654D01*
X1012711Y447821D01*
X1011471Y447196D01*
X1008371D01*
G01X921881Y347196D02*
Y359696D01*
X925601D01*
X926841Y359071D01*
X927771Y357613D01*
X928081Y355946D01*
X927771Y354279D01*
X926996Y353029D01*
X925601Y352404D01*
X921881D01*
G01X934281Y359696D02*
Y347196D01*
X940481D01*
G01X945906D02*
X949781Y359696D01*
X953656Y347196D01*
G01X952261Y351571D02*
X947301D01*
G01X962181Y359696D02*
Y347196D01*
G01X958616Y359696D02*
X965746D01*
G01X977681Y347196D02*
X971481D01*
Y359696D01*
X977681D01*
G01X975201Y353654D02*
X971481D01*
G01X983571Y347196D02*
Y359696D01*
X986671D01*
X987911Y359071D01*
X988841Y358238D01*
X989616Y356988D01*
X990236Y355529D01*
X990391Y353446D01*
X990236Y351363D01*
X989616Y349904D01*
X988841Y348654D01*
X987911Y347821D01*
X986671Y347196D01*
X983571D01*
G01X921881Y472196D02*
Y484696D01*
X925601D01*
X926841Y484071D01*
X927771Y482613D01*
X928081Y480946D01*
X927771Y479279D01*
X926996Y478029D01*
X925601Y477404D01*
X921881D01*
G01X934281Y484696D02*
Y472196D01*
X940481D01*
G01X945906D02*
X949781Y484696D01*
X953656Y472196D01*
G01X952261Y476571D02*
X947301D01*
G01X962181Y484696D02*
Y472196D01*
G01X958616Y484696D02*
X965746D01*
G01X977681Y472196D02*
X971481D01*
Y484696D01*
X977681D01*
G01X975201Y478654D02*
X971481D01*
G01X983571Y472196D02*
Y484696D01*
X986671D01*
X987911Y484071D01*
X988841Y483238D01*
X989616Y481988D01*
X990236Y480529D01*
X990391Y478446D01*
X990236Y476363D01*
X989616Y474904D01*
X988841Y473654D01*
X987911Y472821D01*
X986671Y472196D01*
X983571D01*
G01X921881Y497196D02*
Y509696D01*
X925601D01*
X926841Y509071D01*
X927771Y507613D01*
X928081Y505946D01*
X927771Y504279D01*
X926996Y503029D01*
X925601Y502404D01*
X921881D01*
G01X934281Y509696D02*
Y497196D01*
X940481D01*
G01X945906D02*
X949781Y509696D01*
X953656Y497196D01*
G01X952261Y501571D02*
X947301D01*
G01X962181Y509696D02*
Y497196D01*
G01X958616Y509696D02*
X965746D01*
G01X977681Y497196D02*
X971481D01*
Y509696D01*
X977681D01*
G01X975201Y503654D02*
X971481D01*
G01X983571Y497196D02*
Y509696D01*
X986671D01*
X987911Y509071D01*
X988841Y508238D01*
X989616Y506988D01*
X990236Y505529D01*
X990391Y503446D01*
X990236Y501363D01*
X989616Y499904D01*
X988841Y498654D01*
X987911Y497821D01*
X986671Y497196D01*
X983571D01*
G01X921881Y522196D02*
Y534696D01*
X925601D01*
X926841Y534071D01*
X927771Y532613D01*
X928081Y530946D01*
X927771Y529279D01*
X926996Y528029D01*
X925601Y527404D01*
X921881D01*
G01X934281Y534696D02*
Y522196D01*
X940481D01*
G01X945906D02*
X949781Y534696D01*
X953656Y522196D01*
G01X952261Y526571D02*
X947301D01*
G01X962181Y534696D02*
Y522196D01*
G01X958616Y534696D02*
X965746D01*
G01X977681Y522196D02*
X971481D01*
Y534696D01*
X977681D01*
G01X975201Y528654D02*
X971481D01*
G01X983571Y522196D02*
Y534696D01*
X986671D01*
X987911Y534071D01*
X988841Y533238D01*
X989616Y531988D01*
X990236Y530529D01*
X990391Y528446D01*
X990236Y526363D01*
X989616Y524904D01*
X988841Y523654D01*
X987911Y522821D01*
X986671Y522196D01*
X983571D01*
G01X921881Y547196D02*
Y559696D01*
X925601D01*
X926841Y559071D01*
X927771Y557613D01*
X928081Y555946D01*
X927771Y554279D01*
X926996Y553029D01*
X925601Y552404D01*
X921881D01*
G01X934281Y559696D02*
Y547196D01*
X940481D01*
G01X945906D02*
X949781Y559696D01*
X953656Y547196D01*
G01X952261Y551571D02*
X947301D01*
G01X962181Y559696D02*
Y547196D01*
G01X958616Y559696D02*
X965746D01*
G01X977681Y547196D02*
X971481D01*
Y559696D01*
X977681D01*
G01X975201Y553654D02*
X971481D01*
G01X983571Y547196D02*
Y559696D01*
X986671D01*
X987911Y559071D01*
X988841Y558238D01*
X989616Y556988D01*
X990236Y555529D01*
X990391Y553446D01*
X990236Y551363D01*
X989616Y549904D01*
X988841Y548654D01*
X987911Y547821D01*
X986671Y547196D01*
X983571D01*
G01X921881Y572196D02*
Y584696D01*
X925601D01*
X926841Y584071D01*
X927771Y582613D01*
X928081Y580946D01*
X927771Y579279D01*
X926996Y578029D01*
X925601Y577404D01*
X921881D01*
G01X934281Y584696D02*
Y572196D01*
X940481D01*
G01X945906D02*
X949781Y584696D01*
X953656Y572196D01*
G01X952261Y576571D02*
X947301D01*
G01X962181Y584696D02*
Y572196D01*
G01X958616Y584696D02*
X965746D01*
G01X977681Y572196D02*
X971481D01*
Y584696D01*
X977681D01*
G01X975201Y578654D02*
X971481D01*
G01X983571Y572196D02*
Y584696D01*
X986671D01*
X987911Y584071D01*
X988841Y583238D01*
X989616Y581988D01*
X990236Y580529D01*
X990391Y578446D01*
X990236Y576363D01*
X989616Y574904D01*
X988841Y573654D01*
X987911Y572821D01*
X986671Y572196D01*
X983571D01*
G01X921881Y597196D02*
Y609696D01*
X925601D01*
X926841Y609071D01*
X927771Y607613D01*
X928081Y605946D01*
X927771Y604279D01*
X926996Y603029D01*
X925601Y602404D01*
X921881D01*
G01X934281Y609696D02*
Y597196D01*
X940481D01*
G01X945906D02*
X949781Y609696D01*
X953656Y597196D01*
G01X952261Y601571D02*
X947301D01*
G01X962181Y609696D02*
Y597196D01*
G01X958616Y609696D02*
X965746D01*
G01X977681Y597196D02*
X971481D01*
Y609696D01*
X977681D01*
G01X975201Y603654D02*
X971481D01*
G01X983571Y597196D02*
Y609696D01*
X986671D01*
X987911Y609071D01*
X988841Y608238D01*
X989616Y606988D01*
X990236Y605529D01*
X990391Y603446D01*
X990236Y601363D01*
X989616Y599904D01*
X988841Y598654D01*
X987911Y597821D01*
X986671Y597196D01*
X983571D01*
G01X921881Y622196D02*
Y634696D01*
X925601D01*
X926841Y634071D01*
X927771Y632613D01*
X928081Y630946D01*
X927771Y629279D01*
X926996Y628029D01*
X925601Y627404D01*
X921881D01*
G01X934281Y634696D02*
Y622196D01*
X940481D01*
G01X945906D02*
X949781Y634696D01*
X953656Y622196D01*
G01X952261Y626571D02*
X947301D01*
G01X962181Y634696D02*
Y622196D01*
G01X958616Y634696D02*
X965746D01*
G01X977681Y622196D02*
X971481D01*
Y634696D01*
X977681D01*
G01X975201Y628654D02*
X971481D01*
G01X983571Y622196D02*
Y634696D01*
X986671D01*
X987911Y634071D01*
X988841Y633238D01*
X989616Y631988D01*
X990236Y630529D01*
X990391Y628446D01*
X990236Y626363D01*
X989616Y624904D01*
X988841Y623654D01*
X987911Y622821D01*
X986671Y622196D01*
X983571D01*
G01X921881Y647196D02*
Y659696D01*
X925601D01*
X926841Y659071D01*
X927771Y657613D01*
X928081Y655946D01*
X927771Y654279D01*
X926996Y653029D01*
X925601Y652404D01*
X921881D01*
G01X934281Y659696D02*
Y647196D01*
X940481D01*
G01X945906D02*
X949781Y659696D01*
X953656Y647196D01*
G01X952261Y651571D02*
X947301D01*
G01X962181Y659696D02*
Y647196D01*
G01X958616Y659696D02*
X965746D01*
G01X977681Y647196D02*
X971481D01*
Y659696D01*
X977681D01*
G01X975201Y653654D02*
X971481D01*
G01X983571Y647196D02*
Y659696D01*
X986671D01*
X987911Y659071D01*
X988841Y658238D01*
X989616Y656988D01*
X990236Y655529D01*
X990391Y653446D01*
X990236Y651363D01*
X989616Y649904D01*
X988841Y648654D01*
X987911Y647821D01*
X986671Y647196D01*
X983571D01*
G01X921881Y672196D02*
Y684696D01*
X925601D01*
X926841Y684071D01*
X927771Y682613D01*
X928081Y680946D01*
X927771Y679279D01*
X926996Y678029D01*
X925601Y677404D01*
X921881D01*
G01X934281Y684696D02*
Y672196D01*
X940481D01*
G01X945906D02*
X949781Y684696D01*
X953656Y672196D01*
G01X952261Y676571D02*
X947301D01*
G01X962181Y684696D02*
Y672196D01*
G01X958616Y684696D02*
X965746D01*
G01X977681Y672196D02*
X971481D01*
Y684696D01*
X977681D01*
G01X975201Y678654D02*
X971481D01*
G01X983571Y672196D02*
Y684696D01*
X986671D01*
X987911Y684071D01*
X988841Y683238D01*
X989616Y681988D01*
X990236Y680529D01*
X990391Y678446D01*
X990236Y676363D01*
X989616Y674904D01*
X988841Y673654D01*
X987911Y672821D01*
X986671Y672196D01*
X983571D01*
G01X1019531Y690946D02*
Y340946D01*
G01X1045881Y622196D02*
Y634696D01*
X1044021Y632196D01*
G01Y622196D02*
X1047741D01*
G01X1058281D02*
X1059366Y622404D01*
X1060606Y623029D01*
X1061381Y624071D01*
X1061691Y625529D01*
X1061381Y626987D01*
X1060451Y628238D01*
X1059056Y628863D01*
X1057506D01*
X1056576Y629279D01*
X1055801Y630321D01*
X1055491Y631779D01*
X1055956Y633238D01*
X1057041Y634279D01*
X1058281Y634696D01*
X1059521Y634279D01*
X1060606Y633238D01*
X1061071Y631779D01*
X1060761Y630321D01*
X1059986Y629279D01*
X1059056Y628863D01*
X1057506D01*
X1056111Y628238D01*
X1055181Y626987D01*
X1054871Y625529D01*
X1055181Y624071D01*
X1055956Y623029D01*
X1057196Y622404D01*
X1058281Y622196D01*
G01X1070681D02*
X1071766Y622404D01*
X1073006Y623029D01*
X1073781Y624071D01*
X1074091Y625529D01*
X1073781Y626987D01*
X1072851Y628238D01*
X1071456Y628863D01*
X1069906D01*
X1068976Y629279D01*
X1068201Y630321D01*
X1067891Y631779D01*
X1068356Y633238D01*
X1069441Y634279D01*
X1070681Y634696D01*
X1071921Y634279D01*
X1073006Y633238D01*
X1073471Y631779D01*
X1073161Y630321D01*
X1072386Y629279D01*
X1071456Y628863D01*
X1069906D01*
X1068511Y628238D01*
X1067581Y626987D01*
X1067271Y625529D01*
X1067581Y624071D01*
X1068356Y623029D01*
X1069596Y622404D01*
X1070681Y622196D01*
G01X1045881Y672196D02*
X1044641Y672404D01*
X1043556Y673237D01*
X1042626Y674488D01*
X1042006Y675946D01*
X1041696Y677613D01*
Y679279D01*
X1042006Y680946D01*
X1042626Y682404D01*
X1043556Y683654D01*
X1044641Y684488D01*
X1045881Y684696D01*
X1047121Y684488D01*
X1048206Y683654D01*
X1049136Y682404D01*
X1049756Y680946D01*
X1050066Y679279D01*
Y677613D01*
X1049756Y675946D01*
X1049136Y674488D01*
X1048206Y673237D01*
X1047121Y672404D01*
X1045881Y672196D01*
G01X1047121Y675529D02*
X1048981Y672196D01*
G01X1058281Y684696D02*
Y672196D01*
G01X1054716Y684696D02*
X1061846D01*
G01X1070681Y672196D02*
Y677821D01*
X1067581Y684696D01*
G01X1073781D02*
X1070681Y677821D01*
G01X1060141Y347196D02*
Y359696D01*
X1054406Y350738D01*
X1062156D01*
G01X1052081Y372196D02*
Y384696D01*
X1050221Y382196D01*
G01Y372196D02*
X1053941D01*
G01X1064481D02*
Y384696D01*
X1062621Y382196D01*
G01Y372196D02*
X1066341D01*
G01X1060141Y397196D02*
Y409696D01*
X1054406Y400738D01*
X1062156D01*
G01X1055336Y432613D02*
X1056266Y433862D01*
X1057351Y434488D01*
X1058591Y434696D01*
X1060141Y434279D01*
X1061226Y433238D01*
X1061536Y431988D01*
X1061381Y430737D01*
X1060761Y429696D01*
X1057661Y427613D01*
X1056266Y426154D01*
X1055336Y424071D01*
X1055026Y422196D01*
X1061536D01*
G01X1055336Y457613D02*
X1056266Y458862D01*
X1057351Y459488D01*
X1058591Y459696D01*
X1060141Y459279D01*
X1061226Y458238D01*
X1061536Y456988D01*
X1061381Y455737D01*
X1060761Y454696D01*
X1057661Y452613D01*
X1056266Y451154D01*
X1055336Y449071D01*
X1055026Y447196D01*
X1061536D01*
G01X1055336Y482613D02*
X1056266Y483862D01*
X1057351Y484488D01*
X1058591Y484696D01*
X1060141Y484279D01*
X1061226Y483238D01*
X1061536Y481988D01*
X1061381Y480737D01*
X1060761Y479696D01*
X1057661Y477613D01*
X1056266Y476154D01*
X1055336Y474071D01*
X1055026Y472196D01*
X1061536D01*
G01X1060141Y497196D02*
Y509696D01*
X1054406Y500738D01*
X1062156D01*
G01X1058281Y522196D02*
X1059366Y522404D01*
X1060606Y523029D01*
X1061381Y524071D01*
X1061691Y525529D01*
X1061381Y526987D01*
X1060451Y528238D01*
X1059056Y528863D01*
X1057506D01*
X1056576Y529279D01*
X1055801Y530321D01*
X1055491Y531779D01*
X1055956Y533238D01*
X1057041Y534279D01*
X1058281Y534696D01*
X1059521Y534279D01*
X1060606Y533238D01*
X1061071Y531779D01*
X1060761Y530321D01*
X1059986Y529279D01*
X1059056Y528863D01*
X1057506D01*
X1056111Y528238D01*
X1055181Y526987D01*
X1054871Y525529D01*
X1055181Y524071D01*
X1055956Y523029D01*
X1057196Y522404D01*
X1058281Y522196D01*
G01X1060141Y547196D02*
Y559696D01*
X1054406Y550738D01*
X1062156D01*
G01X1052081Y572196D02*
X1053166Y572404D01*
X1054406Y573029D01*
X1055181Y574071D01*
X1055491Y575529D01*
X1055181Y576987D01*
X1054251Y578238D01*
X1052856Y578863D01*
X1051306D01*
X1050376Y579279D01*
X1049601Y580321D01*
X1049291Y581779D01*
X1049756Y583238D01*
X1050841Y584279D01*
X1052081Y584696D01*
X1053321Y584279D01*
X1054406Y583238D01*
X1054871Y581779D01*
X1054561Y580321D01*
X1053786Y579279D01*
X1052856Y578863D01*
X1051306D01*
X1049911Y578238D01*
X1048981Y576987D01*
X1048671Y575529D01*
X1048981Y574071D01*
X1049756Y573029D01*
X1050996Y572404D01*
X1052081Y572196D01*
G01X1064481D02*
X1065566Y572404D01*
X1066806Y573029D01*
X1067581Y574071D01*
X1067891Y575529D01*
X1067581Y576987D01*
X1066651Y578238D01*
X1065256Y578863D01*
X1063706D01*
X1062776Y579279D01*
X1062001Y580321D01*
X1061691Y581779D01*
X1062156Y583238D01*
X1063241Y584279D01*
X1064481Y584696D01*
X1065721Y584279D01*
X1066806Y583238D01*
X1067271Y581779D01*
X1066961Y580321D01*
X1066186Y579279D01*
X1065256Y578863D01*
X1063706D01*
X1062311Y578238D01*
X1061381Y576987D01*
X1061071Y575529D01*
X1061381Y574071D01*
X1062156Y573029D01*
X1063396Y572404D01*
X1064481Y572196D01*
G01X1049136Y607613D02*
X1050066Y608862D01*
X1051151Y609488D01*
X1052391Y609696D01*
X1053941Y609279D01*
X1055026Y608238D01*
X1055336Y606988D01*
X1055181Y605737D01*
X1054561Y604696D01*
X1051461Y602613D01*
X1050066Y601154D01*
X1049136Y599071D01*
X1048826Y597196D01*
X1055336D01*
G01X1064481D02*
X1065566Y597404D01*
X1066806Y598029D01*
X1067581Y599071D01*
X1067891Y600529D01*
X1067581Y601987D01*
X1066651Y603238D01*
X1065256Y603863D01*
X1063706D01*
X1062776Y604279D01*
X1062001Y605321D01*
X1061691Y606779D01*
X1062156Y608238D01*
X1063241Y609279D01*
X1064481Y609696D01*
X1065721Y609279D01*
X1066806Y608238D01*
X1067271Y606779D01*
X1066961Y605321D01*
X1066186Y604279D01*
X1065256Y603863D01*
X1063706D01*
X1062311Y603238D01*
X1061381Y601987D01*
X1061071Y600529D01*
X1061381Y599071D01*
X1062156Y598029D01*
X1063396Y597404D01*
X1064481Y597196D01*
G01X1048671Y649071D02*
X1049601Y648029D01*
X1050686Y647404D01*
X1052081Y647196D01*
X1053476Y647613D01*
X1054561Y648446D01*
X1055336Y649904D01*
X1055491Y651571D01*
X1055181Y653238D01*
X1054406Y654279D01*
X1053321Y655113D01*
X1052236Y655321D01*
X1051151Y655113D01*
X1049756Y654279D01*
X1050221Y659696D01*
X1054406D01*
G01X1066341Y647196D02*
Y659696D01*
X1060606Y650738D01*
X1068356D01*
G01X-25590Y9843D02*
G03X-15748Y0I9842J-1D01*
G01X-25590Y89370D02*
Y9843D01*
G01X-23622Y91339D02*
G03X-25590Y89370I1J-1969D01*
G01X-7874Y91339D02*
X-23622D01*
G01X-25590Y109055D02*
G03X-21653Y105118I3937J0D01*
G01X-25590Y357874D02*
Y109055D01*
G01X-21653Y105118D02*
X261811D01*
G01X-25590Y371654D02*
G03X-23622Y369685I1968J-1D01*
G01X-21653Y361811D02*
G03X-25590Y357874I0J-3937D01*
G01X1969Y361811D02*
X-21653D01*
G01X-7874Y369685D02*
X-23622D01*
G01X-25590Y459055D02*
Y371654D01*
G01X-23622Y461024D02*
G03X-25590Y459055I1J-1969D01*
G01X-7874Y461024D02*
X-23622D01*
G01X-25590Y478740D02*
G03X-21653Y474803I3937J0D01*
G01X-25590Y727559D02*
Y478740D01*
G01X-21653Y474803D02*
X261811D01*
G01X-21653Y731496D02*
G03X-25590Y727559I0J-3937D01*
G01X1969Y731496D02*
X-21653D01*
G01X-11811Y0D02*
G03X-7874Y3937I0J3937D01*
G01X-11811Y0D02*
X-15748D01*
G01X0Y3937D02*
G03X3937Y0I3937J0D01*
G01X-7874Y33071D02*
Y3937D01*
G01X0Y87402D02*
Y3937D01*
G01Y33071D02*
G03X-7874I-3937J0D01*
G01Y58268D02*
G03X0I3937J0D01*
G01X-7874Y91339D02*
Y58268D01*
G01X3937Y91339D02*
G03X0Y87402I0J-3937D01*
G01X5906Y357874D02*
G03X1969Y361811I-3937J0D01*
G01X0Y373622D02*
G03X3937Y369685I3937J0D01*
G01X-7874Y402756D02*
Y369685D01*
G01X0Y457087D02*
Y373622D01*
G01Y402756D02*
G03X-7874I-3937J0D01*
G01Y427953D02*
G03X0I3937J0D01*
G01X-7874Y461024D02*
Y427953D01*
G01X3937Y461024D02*
G03X0Y457087I0J-3937D01*
G01X5906Y727559D02*
G03X1969Y731496I-3937J0D01*
G01X3937Y0D02*
X372048D01*
G01X192914Y91339D02*
X3937D01*
G01X5906Y290748D02*
G03X9843Y286811I3937J0D01*
G01X5906Y357874D02*
Y290748D01*
G01X69488Y286811D02*
X9843D01*
G01X13780Y315650D02*
Y294685D01*
G01X69488D02*
X13780D01*
G01Y315650D02*
G03X5906I-3937J0D01*
G01Y340847D02*
G03X13780I3937J0D01*
G01Y361811D02*
Y340847D01*
G01X3937Y369685D02*
X372048D01*
G01X43307Y361811D02*
X13780D01*
G01X192914Y461024D02*
X3937D01*
G01X5906Y660433D02*
G03X9843Y656496I3937J0D01*
G01X5906Y727559D02*
Y660433D01*
G01X69488Y656496D02*
X9843D01*
G01X13780Y685335D02*
Y664370D01*
G01X69488D02*
X13780D01*
G01Y685335D02*
G03X5906I-3937J0D01*
G01Y710532D02*
G03X13780I3937J0D01*
G01Y729528D02*
Y710532D01*
G01X15748Y731496D02*
G03X13780Y729528I0J-1968D01*
G01X44819Y731496D02*
X15748D01*
G01X259520Y36089D02*
Y32089D01*
X257920D01*
X257387Y32289D01*
X256987Y32756D01*
X256854Y33289D01*
X256987Y33822D01*
X257320Y34222D01*
X257920Y34422D01*
X259520D01*
G01X254520Y36089D02*
Y33422D01*
G01Y33956D02*
X254187Y33689D01*
X253854Y33489D01*
X253387Y33422D01*
X253054Y33489D01*
X252654Y33689D01*
G01X249987Y34289D02*
X247854D01*
X248054Y33822D01*
X248387Y33556D01*
X248854Y33422D01*
X249320Y33489D01*
X249720Y33689D01*
X249987Y34156D01*
X250120Y34556D01*
Y34956D01*
X249987Y35356D01*
X249654Y35756D01*
X249254Y36022D01*
X248787Y36089D01*
X248320Y35956D01*
X247854Y35556D01*
G01X245387Y35622D02*
X245054Y35889D01*
X244587Y36089D01*
X244187D01*
X243787Y35956D01*
X243520Y35756D01*
X243387Y35489D01*
X243454Y35089D01*
X243720Y34889D01*
X244920Y34489D01*
X245187Y34022D01*
X245054Y33689D01*
X244787Y33489D01*
X244387Y33422D01*
X243987Y33489D01*
X243587Y33689D01*
G01X240787Y35622D02*
X240454Y35889D01*
X239987Y36089D01*
X239587D01*
X239187Y35956D01*
X238920Y35756D01*
X238787Y35489D01*
X238854Y35089D01*
X239120Y34889D01*
X240320Y34489D01*
X240587Y34022D01*
X240454Y33689D01*
X240187Y33489D01*
X239787Y33422D01*
X239387Y33489D01*
X238987Y33689D01*
G01X236054Y34756D02*
X234320D01*
G01X230987Y36089D02*
Y32689D01*
X230854Y32356D01*
X230587Y32156D01*
X230187Y32089D01*
X229787Y32222D01*
X229587Y32556D01*
G01X230387Y33689D02*
X231720D01*
G01X225987Y33422D02*
Y36089D01*
G01Y32356D02*
X226120Y32289D01*
Y32156D01*
X225987Y32089D01*
X225854Y32156D01*
Y32289D01*
X225987Y32356D01*
G01X221387Y32089D02*
Y36089D01*
G01X222320Y33422D02*
X220454D01*
G01X213520Y36089D02*
Y32089D01*
X211920D01*
X211387Y32289D01*
X210987Y32756D01*
X210854Y33289D01*
X210987Y33822D01*
X211320Y34222D01*
X211920Y34422D01*
X213520D01*
G01X207587Y32089D02*
Y36089D01*
G01X209120Y32089D02*
X206054D01*
G01X204387Y36089D02*
Y32089D01*
G01X201587D02*
Y36089D01*
G01Y34089D02*
X204387D01*
G01X194920Y36089D02*
Y32089D01*
G01X192787Y33422D02*
X194920Y34956D01*
G01X194054Y34356D02*
X192654Y36089D01*
G01X190187Y34289D02*
X188054D01*
X188254Y33822D01*
X188587Y33556D01*
X189054Y33422D01*
X189520Y33489D01*
X189920Y33689D01*
X190187Y34156D01*
X190320Y34556D01*
Y34956D01*
X190187Y35356D01*
X189854Y35756D01*
X189454Y36022D01*
X188987Y36089D01*
X188520Y35956D01*
X188054Y35556D01*
G01X185587Y34289D02*
X183454D01*
X183654Y33822D01*
X183987Y33556D01*
X184454Y33422D01*
X184920Y33489D01*
X185320Y33689D01*
X185587Y34156D01*
X185720Y34556D01*
Y34956D01*
X185587Y35356D01*
X185254Y35756D01*
X184854Y36022D01*
X184387Y36089D01*
X183920Y35956D01*
X183454Y35556D01*
G01X181187Y37422D02*
Y33422D01*
G01Y34022D02*
X180854Y33689D01*
X180520Y33489D01*
X179987Y33422D01*
X179520Y33489D01*
X179054Y33822D01*
X178854Y34289D01*
X178787Y34756D01*
X178854Y35222D01*
X179054Y35689D01*
X179454Y35956D01*
X179987Y36089D01*
X180454Y36022D01*
X180920Y35822D01*
X181187Y35556D01*
G01X171920Y36089D02*
Y32089D01*
G01Y34022D02*
X171587Y33689D01*
X171254Y33489D01*
X170720Y33422D01*
X170320Y33489D01*
X169854Y33756D01*
X169654Y34156D01*
Y36089D01*
G01X166187D02*
X166587Y36022D01*
X166987Y35756D01*
X167254Y35289D01*
X167387Y34756D01*
X167254Y34222D01*
X166987Y33756D01*
X166587Y33489D01*
X166187Y33422D01*
X165787Y33489D01*
X165387Y33756D01*
X165120Y34222D01*
X165054Y34756D01*
X165120Y35289D01*
X165387Y35756D01*
X165787Y36022D01*
X166187Y36089D01*
G01X161587D02*
Y32089D01*
G01X157987Y34289D02*
X155854D01*
X156054Y33822D01*
X156387Y33556D01*
X156854Y33422D01*
X157320Y33489D01*
X157720Y33689D01*
X157987Y34156D01*
X158120Y34556D01*
Y34956D01*
X157987Y35356D01*
X157654Y35756D01*
X157254Y36022D01*
X156787Y36089D01*
X156320Y35956D01*
X155854Y35556D01*
G01X148787Y35622D02*
X148454Y35889D01*
X147987Y36089D01*
X147587D01*
X147187Y35956D01*
X146920Y35756D01*
X146787Y35489D01*
X146854Y35089D01*
X147120Y34889D01*
X148320Y34489D01*
X148587Y34022D01*
X148454Y33689D01*
X148187Y33489D01*
X147787Y33422D01*
X147387Y33489D01*
X146987Y33689D01*
G01X143187Y33422D02*
Y36089D01*
G01Y32356D02*
X143320Y32289D01*
Y32156D01*
X143187Y32089D01*
X143054Y32156D01*
Y32289D01*
X143187Y32356D01*
G01X139587Y33422D02*
X137587D01*
X139587Y36089D01*
X137587D01*
G01X134987Y34289D02*
X132854D01*
X133054Y33822D01*
X133387Y33556D01*
X133854Y33422D01*
X134320Y33489D01*
X134720Y33689D01*
X134987Y34156D01*
X135120Y34556D01*
Y34956D01*
X134987Y35356D01*
X134654Y35756D01*
X134254Y36022D01*
X133787Y36089D01*
X133320Y35956D01*
X132854Y35556D01*
G01X124787Y32089D02*
Y36089D01*
G01X125720Y33422D02*
X123854D01*
G01X120187Y36089D02*
X120587Y36022D01*
X120987Y35756D01*
X121254Y35289D01*
X121387Y34756D01*
X121254Y34222D01*
X120987Y33756D01*
X120587Y33489D01*
X120187Y33422D01*
X119787Y33489D01*
X119387Y33756D01*
X119120Y34222D01*
X119054Y34756D01*
X119120Y35289D01*
X119387Y35756D01*
X119787Y36022D01*
X120187Y36089D01*
G01X115587D02*
Y32089D01*
G01X111987Y34289D02*
X109854D01*
X110054Y33822D01*
X110387Y33556D01*
X110854Y33422D01*
X111320Y33489D01*
X111720Y33689D01*
X111987Y34156D01*
X112120Y34556D01*
Y34956D01*
X111987Y35356D01*
X111654Y35756D01*
X111254Y36022D01*
X110787Y36089D01*
X110320Y35956D01*
X109854Y35556D01*
G01X107320Y36089D02*
Y33422D01*
G01Y33956D02*
X106987Y33689D01*
X106654Y33489D01*
X106187Y33422D01*
X105854Y33489D01*
X105454Y33689D01*
G01X100587Y36089D02*
Y33422D01*
G01Y33889D02*
X100854Y33622D01*
X101254Y33489D01*
X101720Y33422D01*
X102187Y33556D01*
X102587Y33822D01*
X102854Y34222D01*
X102987Y34756D01*
X102854Y35289D01*
X102587Y35689D01*
X102187Y35956D01*
X101720Y36089D01*
X101254Y36022D01*
X100854Y35822D01*
X100587Y35556D01*
G01X98320Y36089D02*
Y33422D01*
G01Y34089D02*
X98054Y33756D01*
X97654Y33489D01*
X97120Y33422D01*
X96654Y33489D01*
X96254Y33756D01*
X96054Y34222D01*
Y36089D01*
G01X91520Y33756D02*
X91987Y33489D01*
X92387Y33422D01*
X92920Y33556D01*
X93320Y33822D01*
X93587Y34289D01*
X93654Y34756D01*
X93587Y35222D01*
X93320Y35622D01*
X92920Y35956D01*
X92387Y36089D01*
X91920Y35956D01*
X91520Y35689D01*
G01X88987Y34289D02*
X86854D01*
X87054Y33822D01*
X87387Y33556D01*
X87854Y33422D01*
X88320Y33489D01*
X88720Y33689D01*
X88987Y34156D01*
X89120Y34556D01*
Y34956D01*
X88987Y35356D01*
X88654Y35756D01*
X88254Y36022D01*
X87787Y36089D01*
X87320Y35956D01*
X86854Y35556D01*
G01X79520Y34756D02*
X77920D01*
G01X78787Y33889D02*
Y35622D01*
G01X75387Y36222D02*
X72987Y32089D01*
G01X70454Y34756D02*
X68720D01*
G01X66254Y32756D02*
X65854Y32356D01*
X65387Y32156D01*
X64854Y32089D01*
X64187Y32222D01*
X63720Y32556D01*
X63587Y32956D01*
X63654Y33356D01*
X63920Y33689D01*
X65254Y34356D01*
X65854Y34822D01*
X66254Y35489D01*
X66387Y36089D01*
X63587D01*
G01X57787D02*
Y33422D01*
G01Y34156D02*
X57587Y33822D01*
X57254Y33556D01*
X56787Y33422D01*
X56320Y33556D01*
X55987Y33822D01*
X55787Y34156D01*
Y36089D01*
G01Y34156D02*
X55587Y33822D01*
X55254Y33556D01*
X54787Y33422D01*
X54320Y33556D01*
X53987Y33822D01*
X53787Y34222D01*
Y36089D01*
G01X51187Y33422D02*
Y36089D01*
G01Y32356D02*
X51320Y32289D01*
Y32156D01*
X51187Y32089D01*
X51054Y32156D01*
Y32289D01*
X51187Y32356D01*
G01X46587Y36089D02*
Y32089D01*
G01X42987Y35622D02*
X42654Y35889D01*
X42187Y36089D01*
X41787D01*
X41387Y35956D01*
X41120Y35756D01*
X40987Y35489D01*
X41054Y35089D01*
X41320Y34889D01*
X42520Y34489D01*
X42787Y34022D01*
X42654Y33689D01*
X42387Y33489D01*
X41987Y33422D01*
X41587Y33489D01*
X41187Y33689D01*
G01X259520Y80578D02*
Y76578D01*
X257920D01*
X257387Y76778D01*
X256987Y77245D01*
X256854Y77778D01*
X256987Y78311D01*
X257320Y78711D01*
X257920Y78911D01*
X259520D01*
G01X254520Y80578D02*
Y77911D01*
G01Y78445D02*
X254187Y78178D01*
X253854Y77978D01*
X253387Y77911D01*
X253054Y77978D01*
X252654Y78178D01*
G01X249987Y78778D02*
X247854D01*
X248054Y78311D01*
X248387Y78045D01*
X248854Y77911D01*
X249320Y77978D01*
X249720Y78178D01*
X249987Y78645D01*
X250120Y79045D01*
Y79445D01*
X249987Y79845D01*
X249654Y80245D01*
X249254Y80511D01*
X248787Y80578D01*
X248320Y80445D01*
X247854Y80045D01*
G01X245387Y80111D02*
X245054Y80378D01*
X244587Y80578D01*
X244187D01*
X243787Y80445D01*
X243520Y80245D01*
X243387Y79978D01*
X243454Y79578D01*
X243720Y79378D01*
X244920Y78978D01*
X245187Y78511D01*
X245054Y78178D01*
X244787Y77978D01*
X244387Y77911D01*
X243987Y77978D01*
X243587Y78178D01*
G01X240787Y80111D02*
X240454Y80378D01*
X239987Y80578D01*
X239587D01*
X239187Y80445D01*
X238920Y80245D01*
X238787Y79978D01*
X238854Y79578D01*
X239120Y79378D01*
X240320Y78978D01*
X240587Y78511D01*
X240454Y78178D01*
X240187Y77978D01*
X239787Y77911D01*
X239387Y77978D01*
X238987Y78178D01*
G01X236054Y79245D02*
X234320D01*
G01X230987Y80578D02*
Y77178D01*
X230854Y76845D01*
X230587Y76645D01*
X230187Y76578D01*
X229787Y76711D01*
X229587Y77045D01*
G01X230387Y78178D02*
X231720D01*
G01X225987Y77911D02*
Y80578D01*
G01Y76845D02*
X226120Y76778D01*
Y76645D01*
X225987Y76578D01*
X225854Y76645D01*
Y76778D01*
X225987Y76845D01*
G01X221387Y76578D02*
Y80578D01*
G01X222320Y77911D02*
X220454D01*
G01X213520Y80578D02*
Y76578D01*
X211920D01*
X211387Y76778D01*
X210987Y77245D01*
X210854Y77778D01*
X210987Y78311D01*
X211320Y78711D01*
X211920Y78911D01*
X213520D01*
G01X207587Y76578D02*
Y80578D01*
G01X209120Y76578D02*
X206054D01*
G01X204387Y80578D02*
Y76578D01*
G01X201587D02*
Y80578D01*
G01Y78578D02*
X204387D01*
G01X194920Y80578D02*
Y76578D01*
G01X192787Y77911D02*
X194920Y79445D01*
G01X194054Y78845D02*
X192654Y80578D01*
G01X190187Y78778D02*
X188054D01*
X188254Y78311D01*
X188587Y78045D01*
X189054Y77911D01*
X189520Y77978D01*
X189920Y78178D01*
X190187Y78645D01*
X190320Y79045D01*
Y79445D01*
X190187Y79845D01*
X189854Y80245D01*
X189454Y80511D01*
X188987Y80578D01*
X188520Y80445D01*
X188054Y80045D01*
G01X185587Y78778D02*
X183454D01*
X183654Y78311D01*
X183987Y78045D01*
X184454Y77911D01*
X184920Y77978D01*
X185320Y78178D01*
X185587Y78645D01*
X185720Y79045D01*
Y79445D01*
X185587Y79845D01*
X185254Y80245D01*
X184854Y80511D01*
X184387Y80578D01*
X183920Y80445D01*
X183454Y80045D01*
G01X181187Y81911D02*
Y77911D01*
G01Y78511D02*
X180854Y78178D01*
X180520Y77978D01*
X179987Y77911D01*
X179520Y77978D01*
X179054Y78311D01*
X178854Y78778D01*
X178787Y79245D01*
X178854Y79711D01*
X179054Y80178D01*
X179454Y80445D01*
X179987Y80578D01*
X180454Y80511D01*
X180920Y80311D01*
X181187Y80045D01*
G01X171920Y80578D02*
Y76578D01*
G01Y78511D02*
X171587Y78178D01*
X171254Y77978D01*
X170720Y77911D01*
X170320Y77978D01*
X169854Y78245D01*
X169654Y78645D01*
Y80578D01*
G01X166187D02*
X166587Y80511D01*
X166987Y80245D01*
X167254Y79778D01*
X167387Y79245D01*
X167254Y78711D01*
X166987Y78245D01*
X166587Y77978D01*
X166187Y77911D01*
X165787Y77978D01*
X165387Y78245D01*
X165120Y78711D01*
X165054Y79245D01*
X165120Y79778D01*
X165387Y80245D01*
X165787Y80511D01*
X166187Y80578D01*
G01X161587D02*
Y76578D01*
G01X157987Y78778D02*
X155854D01*
X156054Y78311D01*
X156387Y78045D01*
X156854Y77911D01*
X157320Y77978D01*
X157720Y78178D01*
X157987Y78645D01*
X158120Y79045D01*
Y79445D01*
X157987Y79845D01*
X157654Y80245D01*
X157254Y80511D01*
X156787Y80578D01*
X156320Y80445D01*
X155854Y80045D01*
G01X148787Y80111D02*
X148454Y80378D01*
X147987Y80578D01*
X147587D01*
X147187Y80445D01*
X146920Y80245D01*
X146787Y79978D01*
X146854Y79578D01*
X147120Y79378D01*
X148320Y78978D01*
X148587Y78511D01*
X148454Y78178D01*
X148187Y77978D01*
X147787Y77911D01*
X147387Y77978D01*
X146987Y78178D01*
G01X143187Y77911D02*
Y80578D01*
G01Y76845D02*
X143320Y76778D01*
Y76645D01*
X143187Y76578D01*
X143054Y76645D01*
Y76778D01*
X143187Y76845D01*
G01X139587Y77911D02*
X137587D01*
X139587Y80578D01*
X137587D01*
G01X134987Y78778D02*
X132854D01*
X133054Y78311D01*
X133387Y78045D01*
X133854Y77911D01*
X134320Y77978D01*
X134720Y78178D01*
X134987Y78645D01*
X135120Y79045D01*
Y79445D01*
X134987Y79845D01*
X134654Y80245D01*
X134254Y80511D01*
X133787Y80578D01*
X133320Y80445D01*
X132854Y80045D01*
G01X124787Y76578D02*
Y80578D01*
G01X125720Y77911D02*
X123854D01*
G01X120187Y80578D02*
X120587Y80511D01*
X120987Y80245D01*
X121254Y79778D01*
X121387Y79245D01*
X121254Y78711D01*
X120987Y78245D01*
X120587Y77978D01*
X120187Y77911D01*
X119787Y77978D01*
X119387Y78245D01*
X119120Y78711D01*
X119054Y79245D01*
X119120Y79778D01*
X119387Y80245D01*
X119787Y80511D01*
X120187Y80578D01*
G01X115587D02*
Y76578D01*
G01X111987Y78778D02*
X109854D01*
X110054Y78311D01*
X110387Y78045D01*
X110854Y77911D01*
X111320Y77978D01*
X111720Y78178D01*
X111987Y78645D01*
X112120Y79045D01*
Y79445D01*
X111987Y79845D01*
X111654Y80245D01*
X111254Y80511D01*
X110787Y80578D01*
X110320Y80445D01*
X109854Y80045D01*
G01X107320Y80578D02*
Y77911D01*
G01Y78445D02*
X106987Y78178D01*
X106654Y77978D01*
X106187Y77911D01*
X105854Y77978D01*
X105454Y78178D01*
G01X100587Y80578D02*
Y77911D01*
G01Y78378D02*
X100854Y78111D01*
X101254Y77978D01*
X101720Y77911D01*
X102187Y78045D01*
X102587Y78311D01*
X102854Y78711D01*
X102987Y79245D01*
X102854Y79778D01*
X102587Y80178D01*
X102187Y80445D01*
X101720Y80578D01*
X101254Y80511D01*
X100854Y80311D01*
X100587Y80045D01*
G01X98320Y80578D02*
Y77911D01*
G01Y78578D02*
X98054Y78245D01*
X97654Y77978D01*
X97120Y77911D01*
X96654Y77978D01*
X96254Y78245D01*
X96054Y78711D01*
Y80578D01*
G01X91520Y78245D02*
X91987Y77978D01*
X92387Y77911D01*
X92920Y78045D01*
X93320Y78311D01*
X93587Y78778D01*
X93654Y79245D01*
X93587Y79711D01*
X93320Y80111D01*
X92920Y80445D01*
X92387Y80578D01*
X91920Y80445D01*
X91520Y80178D01*
G01X88987Y78778D02*
X86854D01*
X87054Y78311D01*
X87387Y78045D01*
X87854Y77911D01*
X88320Y77978D01*
X88720Y78178D01*
X88987Y78645D01*
X89120Y79045D01*
Y79445D01*
X88987Y79845D01*
X88654Y80245D01*
X88254Y80511D01*
X87787Y80578D01*
X87320Y80445D01*
X86854Y80045D01*
G01X79520Y79245D02*
X77920D01*
G01X78787Y78378D02*
Y80111D01*
G01X75387Y80711D02*
X72987Y76578D01*
G01X70454Y79245D02*
X68720D01*
G01X66254Y77245D02*
X65854Y76845D01*
X65387Y76645D01*
X64854Y76578D01*
X64187Y76711D01*
X63720Y77045D01*
X63587Y77445D01*
X63654Y77845D01*
X63920Y78178D01*
X65254Y78845D01*
X65854Y79311D01*
X66254Y79978D01*
X66387Y80578D01*
X63587D01*
G01X57787D02*
Y77911D01*
G01Y78645D02*
X57587Y78311D01*
X57254Y78045D01*
X56787Y77911D01*
X56320Y78045D01*
X55987Y78311D01*
X55787Y78645D01*
Y80578D01*
G01Y78645D02*
X55587Y78311D01*
X55254Y78045D01*
X54787Y77911D01*
X54320Y78045D01*
X53987Y78311D01*
X53787Y78711D01*
Y80578D01*
G01X51187Y77911D02*
Y80578D01*
G01Y76845D02*
X51320Y76778D01*
Y76645D01*
X51187Y76578D01*
X51054Y76645D01*
Y76778D01*
X51187Y76845D01*
G01X46587Y80578D02*
Y76578D01*
G01X42987Y80111D02*
X42654Y80378D01*
X42187Y80578D01*
X41787D01*
X41387Y80445D01*
X41120Y80245D01*
X40987Y79978D01*
X41054Y79578D01*
X41320Y79378D01*
X42520Y78978D01*
X42787Y78511D01*
X42654Y78178D01*
X42387Y77978D01*
X41987Y77911D01*
X41587Y77978D01*
X41187Y78178D01*
G01X43307Y361811D02*
G03Y369685I0J3937D01*
G01X46675Y730184D02*
G03X44819Y731496I-1856J-657D01*
G01X46675Y730184D02*
G03X54098I3712J1313D01*
G01X73287Y10039D02*
X63287D01*
Y20039D01*
X73287D01*
Y10039D01*
G01X67982Y20439D02*
X67985Y31539D01*
G01X66488Y25439D02*
X67982Y20439D01*
X69478Y25439D01*
X66488D01*
G01X73287Y54528D02*
X63287D01*
Y64528D01*
X73287D01*
Y54528D01*
G01X67982Y64928D02*
X67985Y76028D01*
G01X66488Y69928D02*
X67982Y64928D01*
X69478Y69928D01*
X66488D01*
G01X53150Y181697D02*
G03X55118Y179729I1968J0D01*
G01X53150Y195477D02*
Y181697D01*
G01X55118Y179729D02*
X161418D01*
G01X55118Y197445D02*
G03X53150Y195477I0J-1968D01*
G01X161418Y197445D02*
X55118D01*
G01X73426Y282874D02*
G03X69488Y286811I-3937J0D01*
G01X81300Y282874D02*
G03X69488Y294685I-11811J0D01*
G01X74016Y369685D02*
G03Y361811I0J-3937D01*
G01X53150Y551382D02*
G03X55118Y549414I1968J0D01*
G01X53150Y565162D02*
Y551382D01*
G01X55118Y549414D02*
X161418D01*
G01X55118Y567130D02*
G03X53150Y565162I0J-1968D01*
G01X161418Y567130D02*
X55118D01*
G01X73426Y652559D02*
G03X69488Y656496I-3937J0D01*
G01X81300Y652559D02*
G03X69488Y664370I-11811J0D01*
G01X55954Y731496D02*
G03X54098Y730184I0J-1969D01*
G01X153544Y731496D02*
X55954D01*
G01X121887Y6339D02*
Y13239D01*
X84387D01*
Y6339D01*
X121887D01*
G01X80709Y43307D02*
G03X82677Y41339I1968J0D01*
G01Y47244D02*
G03X80709Y45276I0J-1968D01*
G01X188977Y47244D02*
X82677D01*
G01Y41339D02*
X188977D01*
G01X80709Y45276D02*
Y43307D01*
G01X121887Y50828D02*
Y57728D01*
X84387D01*
Y50828D01*
X121887D01*
G01X86614Y101181D02*
G03X82677Y105118I-3937J0D01*
G01X86614Y95276D02*
Y101181D01*
G01X82677Y91339D02*
G03X86614Y95276I0J3937D01*
G01X73426Y267323D02*
G03X77363Y263386I3937J0D01*
G01X73426Y267323D02*
Y282874D01*
G01X77363Y263386D02*
X159449D01*
G01X81300Y271260D02*
Y282874D01*
G01Y271260D02*
X155512D01*
G01Y361811D02*
X74016D01*
G01X80709Y412992D02*
G03X82677Y411024I1968J0D01*
G01Y416929D02*
G03X80709Y414961I0J-1968D01*
G01X188977Y416929D02*
X82677D01*
G01Y411024D02*
X188977D01*
G01X80709Y414961D02*
Y412992D01*
G01X86614Y464961D02*
Y470866D01*
G01X82677Y461024D02*
G03X86614Y464961I0J3937D01*
G01Y470866D02*
G03X82677Y474803I-3937J0D01*
G01X73426Y637008D02*
G03X77363Y633071I3937J0D01*
G01X73426Y637008D02*
Y652559D01*
G01X77363Y633071D02*
X159449D01*
G01X81300Y640945D02*
Y652559D01*
G01Y640945D02*
X155512D01*
G01X104033Y13239D02*
X103987Y33639D01*
G01X102527Y18236D02*
X104033Y13239D01*
X105517Y18242D01*
X102527Y18236D01*
G01X104033Y57728D02*
X103987Y78128D01*
G01X102527Y62725D02*
X104033Y57728D01*
X105517Y62731D01*
X102527Y62725D01*
G01X109449Y95276D02*
Y101181D01*
G01X113386Y105118D02*
G03X109449Y101181I0J-3937D01*
G01Y95276D02*
G03X113386Y91339I3937J0D01*
G01X109449Y464961D02*
Y470866D01*
G01Y464961D02*
G03X113386Y461024I3937J0D01*
G01Y474803D02*
G03X109449Y470866I0J-3937D01*
G01X217187Y6039D02*
Y13439D01*
X139787D01*
Y5939D01*
X217087D01*
G01X131857Y26339D02*
X131887Y33739D01*
G01X130382Y31345D02*
X131857Y26339D01*
X133372Y31333D01*
X130382Y31345D01*
G01X142687Y20639D02*
Y26339D01*
X118687D01*
Y20639D01*
X142687D01*
G01X217187Y50528D02*
Y57928D01*
X139787D01*
Y50428D01*
X217087D01*
G01X131857Y70828D02*
X131887Y78228D01*
G01X130382Y75834D02*
X131857Y70828D01*
X133372Y75822D01*
X130382Y75834D01*
G01X142687Y65128D02*
Y70828D01*
X118687D01*
Y65128D01*
X142687D01*
G01X162488Y18439D02*
X163982Y13439D01*
X165478Y18439D01*
X162488D01*
G01Y62928D02*
X163982Y57928D01*
X165478Y62928D01*
X162488D01*
G01X161418Y179729D02*
G03X163386Y181697I0J1968D01*
G01Y195477D02*
G03X161418Y197445I-1968J0D01*
G01X159449Y263386D02*
G03X163386Y267323I0J3937D01*
G01X155512Y303937D02*
Y271260D01*
G01X163386Y303937D02*
G03X155512I-3937J0D01*
G01Y329134D02*
G03X163386I3937J0D01*
G01X155512Y361811D02*
Y329134D01*
G01X161418Y549414D02*
G03X163386Y551382I0J1968D01*
G01Y565162D02*
G03X161418Y567130I-1968J0D01*
G01X159449Y633071D02*
G03X163386Y637008I0J3937D01*
G01X155512Y673622D02*
Y640945D01*
G01X163386Y673622D02*
G03X155512I-3937J0D01*
G01Y698819D02*
G03X163386I3937J0D01*
G01X155512Y729528D02*
Y698819D01*
G01Y729528D02*
G03X153544Y731496I-1968J0D01*
G01X163982Y13439D02*
X163987Y31939D01*
G01X163982Y57928D02*
X163987Y76428D01*
G01X163386Y181697D02*
Y195477D01*
G01Y357874D02*
Y267323D01*
G01X167323Y361811D02*
G03X163386Y357874I0J-3937D01*
G01X535433Y361811D02*
X167323D01*
G01X163386Y551382D02*
Y565162D01*
G01Y727559D02*
Y637008D01*
G01X167323Y731496D02*
G03X163386Y727559I0J-3937D01*
G01X535433Y731496D02*
X167323D01*
G01X188977Y41339D02*
G03X190945Y43307I0J1968D01*
G01Y45276D02*
G03X188977Y47244I-1968J0D01*
G01X190945Y43307D02*
Y45276D01*
G01X196851Y97244D02*
G03X194882Y95276I0J-1969D01*
G01X192914Y91339D02*
G03X194882Y93307I0J1968D01*
G01X196851Y97244D02*
X269685D01*
G01X194882Y93307D02*
Y95276D01*
G01X188977Y411024D02*
G03X190945Y412992I0J1968D01*
G01Y414961D02*
G03X188977Y416929I-1968J0D01*
G01X190945Y412992D02*
Y414961D01*
G01X196851Y466929D02*
G03X194882Y464961I-1J-1968D01*
G01X192914Y461024D02*
G03X194882Y462992I0J1968D01*
G01D02*
Y464961D01*
G01X196851Y466929D02*
X269685D01*
G01X228787Y10039D02*
X238287D01*
Y19539D01*
X228787D01*
Y10039D01*
G01Y54528D02*
X238287D01*
Y64028D01*
X228787D01*
Y54528D01*
G01X233482Y19939D02*
X233485Y31539D01*
G01X231988Y24939D02*
X233482Y19939D01*
X234978Y24939D01*
X231988D01*
G01X233482Y64428D02*
X233485Y76028D01*
G01X231988Y69428D02*
X233482Y64428D01*
X234978Y69428D01*
X231988D01*
G01X269685Y97244D02*
G03X273622Y101181I0J3937D01*
G01Y252756D02*
Y101181D01*
G01X261811Y105118D02*
G03X265748Y109055I0J3937D01*
G01D02*
Y260630D01*
G01X273622Y165551D02*
G03X265748I-3937J0D01*
G01Y196260D02*
G03X273622I3937J0D01*
G01X269685Y264567D02*
G03X265748Y260630I0J-3937D01*
G01X277559Y256693D02*
G03X273622Y252756I0J-3937D01*
G01X342520Y264567D02*
X269685D01*
G01X254331Y361811D02*
G03Y369685I0J3937D01*
G01X261811Y474803D02*
G03X265748Y478740I0J3937D01*
G01D02*
Y630315D01*
G01X269685Y466929D02*
G03X273622Y470866I0J3937D01*
G01Y622441D02*
Y470866D01*
G01Y535236D02*
G03X265748I-3937J0D01*
G01Y565945D02*
G03X273622I3937J0D01*
G01X277559Y626378D02*
G03X273622Y622441I0J-3937D01*
G01X269685Y634252D02*
G03X265748Y630315I0J-3937D01*
G01X342520Y634252D02*
X269685D01*
G01X290139Y76020D02*
X289739Y76420D01*
X289539Y76887D01*
X289472Y77420D01*
X289605Y78087D01*
X289939Y78554D01*
X290339Y78687D01*
X290739Y78620D01*
X291072Y78354D01*
X291739Y77020D01*
X292205Y76420D01*
X292872Y76020D01*
X293472Y75887D01*
Y78687D01*
G01X289472Y81887D02*
X289605Y81354D01*
X289939Y80954D01*
X290339Y80687D01*
X290872Y80487D01*
X291472Y80420D01*
X292072Y80487D01*
X292605Y80687D01*
X293005Y80954D01*
X293339Y81354D01*
X293472Y81887D01*
X293339Y82420D01*
X293005Y82820D01*
X292605Y83087D01*
X292072Y83287D01*
X291472Y83354D01*
X290872Y83287D01*
X290339Y83087D01*
X289939Y82820D01*
X289605Y82420D01*
X289472Y81887D01*
G01X293472Y85087D02*
X289472Y87887D01*
G01Y85087D02*
X293472Y87887D01*
G01X292872Y89620D02*
X293205Y90020D01*
X293405Y90487D01*
X293472Y91087D01*
X293339Y91687D01*
X293072Y92154D01*
X292605Y92487D01*
X292072Y92554D01*
X291539Y92420D01*
X291205Y92087D01*
X290939Y91620D01*
X290872Y91154D01*
X290939Y90687D01*
X291205Y90087D01*
X289472Y90287D01*
Y92087D01*
G01X293472Y95687D02*
X293405Y96154D01*
X293205Y96687D01*
X292872Y97020D01*
X292405Y97154D01*
X291939Y97020D01*
X291539Y96620D01*
X291339Y96020D01*
Y95354D01*
X291205Y94954D01*
X290872Y94620D01*
X290405Y94487D01*
X289939Y94687D01*
X289605Y95154D01*
X289472Y95687D01*
X289605Y96220D01*
X289939Y96687D01*
X290405Y96887D01*
X290872Y96754D01*
X291205Y96420D01*
X291339Y96020D01*
Y95354D01*
X291539Y94754D01*
X291939Y94354D01*
X292405Y94220D01*
X292872Y94354D01*
X293205Y94687D01*
X293405Y95220D01*
X293472Y95687D01*
G01X561024Y256693D02*
X277559D01*
G01X285040Y369685D02*
G03Y361811I0J-3937D01*
G01X561024Y626378D02*
X277559D01*
G01X339257Y75020D02*
X338857Y75420D01*
X338657Y75887D01*
X338590Y76420D01*
X338723Y77087D01*
X339057Y77554D01*
X339457Y77687D01*
X339857Y77620D01*
X340190Y77354D01*
X340857Y76020D01*
X341323Y75420D01*
X341990Y75020D01*
X342590Y74887D01*
Y77687D01*
G01X338590Y80887D02*
X338723Y80354D01*
X339057Y79954D01*
X339457Y79687D01*
X339990Y79487D01*
X340590Y79420D01*
X341190Y79487D01*
X341723Y79687D01*
X342123Y79954D01*
X342457Y80354D01*
X342590Y80887D01*
X342457Y81420D01*
X342123Y81820D01*
X341723Y82087D01*
X341190Y82287D01*
X340590Y82354D01*
X339990Y82287D01*
X339457Y82087D01*
X339057Y81820D01*
X338723Y81420D01*
X338590Y80887D01*
G01X342590Y84087D02*
X338590Y86887D01*
G01Y84087D02*
X342590Y86887D01*
G01X341990Y88620D02*
X342323Y89020D01*
X342523Y89487D01*
X342590Y90087D01*
X342457Y90687D01*
X342190Y91154D01*
X341723Y91487D01*
X341190Y91554D01*
X340657Y91420D01*
X340323Y91087D01*
X340057Y90620D01*
X339990Y90154D01*
X340057Y89687D01*
X340323Y89087D01*
X338590Y89287D01*
Y91087D01*
G01X342590Y94687D02*
X342523Y95154D01*
X342323Y95687D01*
X341990Y96020D01*
X341523Y96154D01*
X341057Y96020D01*
X340657Y95620D01*
X340457Y95020D01*
Y94354D01*
X340323Y93954D01*
X339990Y93620D01*
X339523Y93487D01*
X339057Y93687D01*
X338723Y94154D01*
X338590Y94687D01*
X338723Y95220D01*
X339057Y95687D01*
X339523Y95887D01*
X339990Y95754D01*
X340323Y95420D01*
X340457Y95020D01*
Y94354D01*
X340657Y93754D01*
X341057Y93354D01*
X341523Y93220D01*
X341990Y93354D01*
X342323Y93687D01*
X342523Y94220D01*
X342590Y94687D01*
G01X550564Y164042D02*
Y160042D01*
X548964D01*
X548431Y160242D01*
X548031Y160709D01*
X547898Y161242D01*
X548031Y161775D01*
X548364Y162175D01*
X548964Y162375D01*
X550564D01*
G01X545564Y164042D02*
Y161375D01*
G01Y161909D02*
X545231Y161642D01*
X544898Y161442D01*
X544431Y161375D01*
X544098Y161442D01*
X543698Y161642D01*
G01X541031Y162242D02*
X538898D01*
X539098Y161775D01*
X539431Y161509D01*
X539898Y161375D01*
X540364Y161442D01*
X540764Y161642D01*
X541031Y162109D01*
X541164Y162509D01*
Y162909D01*
X541031Y163309D01*
X540698Y163709D01*
X540298Y163975D01*
X539831Y164042D01*
X539364Y163909D01*
X538898Y163509D01*
G01X536431Y163575D02*
X536098Y163842D01*
X535631Y164042D01*
X535231D01*
X534831Y163909D01*
X534564Y163709D01*
X534431Y163442D01*
X534498Y163042D01*
X534764Y162842D01*
X535964Y162442D01*
X536231Y161975D01*
X536098Y161642D01*
X535831Y161442D01*
X535431Y161375D01*
X535031Y161442D01*
X534631Y161642D01*
G01X531831Y163575D02*
X531498Y163842D01*
X531031Y164042D01*
X530631D01*
X530231Y163909D01*
X529964Y163709D01*
X529831Y163442D01*
X529898Y163042D01*
X530164Y162842D01*
X531364Y162442D01*
X531631Y161975D01*
X531498Y161642D01*
X531231Y161442D01*
X530831Y161375D01*
X530431Y161442D01*
X530031Y161642D01*
G01X527098Y162709D02*
X525364D01*
G01X522031Y164042D02*
Y160642D01*
X521898Y160309D01*
X521631Y160109D01*
X521231Y160042D01*
X520831Y160175D01*
X520631Y160509D01*
G01X521431Y161642D02*
X522764D01*
G01X517031Y161375D02*
Y164042D01*
G01Y160309D02*
X517164Y160242D01*
Y160109D01*
X517031Y160042D01*
X516898Y160109D01*
Y160242D01*
X517031Y160309D01*
G01X512431Y160042D02*
Y164042D01*
G01X513364Y161375D02*
X511498D01*
G01X504564Y164042D02*
Y160042D01*
X502964D01*
X502431Y160242D01*
X502031Y160709D01*
X501898Y161242D01*
X502031Y161775D01*
X502364Y162175D01*
X502964Y162375D01*
X504564D01*
G01X498631Y160042D02*
Y164042D01*
G01X500164Y160042D02*
X497098D01*
G01X495431Y164042D02*
Y160042D01*
G01X492631D02*
Y164042D01*
G01Y162042D02*
X495431D01*
G01X485964Y164042D02*
Y160042D01*
G01X483831Y161375D02*
X485964Y162909D01*
G01X485098Y162309D02*
X483698Y164042D01*
G01X481231Y162242D02*
X479098D01*
X479298Y161775D01*
X479631Y161509D01*
X480098Y161375D01*
X480564Y161442D01*
X480964Y161642D01*
X481231Y162109D01*
X481364Y162509D01*
Y162909D01*
X481231Y163309D01*
X480898Y163709D01*
X480498Y163975D01*
X480031Y164042D01*
X479564Y163909D01*
X479098Y163509D01*
G01X476631Y162242D02*
X474498D01*
X474698Y161775D01*
X475031Y161509D01*
X475498Y161375D01*
X475964Y161442D01*
X476364Y161642D01*
X476631Y162109D01*
X476764Y162509D01*
Y162909D01*
X476631Y163309D01*
X476298Y163709D01*
X475898Y163975D01*
X475431Y164042D01*
X474964Y163909D01*
X474498Y163509D01*
G01X472231Y165375D02*
Y161375D01*
G01Y161975D02*
X471898Y161642D01*
X471564Y161442D01*
X471031Y161375D01*
X470564Y161442D01*
X470098Y161775D01*
X469898Y162242D01*
X469831Y162709D01*
X469898Y163175D01*
X470098Y163642D01*
X470498Y163909D01*
X471031Y164042D01*
X471498Y163975D01*
X471964Y163775D01*
X472231Y163509D01*
G01X462964Y164042D02*
Y160042D01*
G01Y161975D02*
X462631Y161642D01*
X462298Y161442D01*
X461764Y161375D01*
X461364Y161442D01*
X460898Y161709D01*
X460698Y162109D01*
Y164042D01*
G01X457231D02*
X457631Y163975D01*
X458031Y163709D01*
X458298Y163242D01*
X458431Y162709D01*
X458298Y162175D01*
X458031Y161709D01*
X457631Y161442D01*
X457231Y161375D01*
X456831Y161442D01*
X456431Y161709D01*
X456164Y162175D01*
X456098Y162709D01*
X456164Y163242D01*
X456431Y163709D01*
X456831Y163975D01*
X457231Y164042D01*
G01X452631D02*
Y160042D01*
G01X449031Y162242D02*
X446898D01*
X447098Y161775D01*
X447431Y161509D01*
X447898Y161375D01*
X448364Y161442D01*
X448764Y161642D01*
X449031Y162109D01*
X449164Y162509D01*
Y162909D01*
X449031Y163309D01*
X448698Y163709D01*
X448298Y163975D01*
X447831Y164042D01*
X447364Y163909D01*
X446898Y163509D01*
G01X439831Y163575D02*
X439498Y163842D01*
X439031Y164042D01*
X438631D01*
X438231Y163909D01*
X437964Y163709D01*
X437831Y163442D01*
X437898Y163042D01*
X438164Y162842D01*
X439364Y162442D01*
X439631Y161975D01*
X439498Y161642D01*
X439231Y161442D01*
X438831Y161375D01*
X438431Y161442D01*
X438031Y161642D01*
G01X434231Y161375D02*
Y164042D01*
G01Y160309D02*
X434364Y160242D01*
Y160109D01*
X434231Y160042D01*
X434098Y160109D01*
Y160242D01*
X434231Y160309D01*
G01X430631Y161375D02*
X428631D01*
X430631Y164042D01*
X428631D01*
G01X426031Y162242D02*
X423898D01*
X424098Y161775D01*
X424431Y161509D01*
X424898Y161375D01*
X425364Y161442D01*
X425764Y161642D01*
X426031Y162109D01*
X426164Y162509D01*
Y162909D01*
X426031Y163309D01*
X425698Y163709D01*
X425298Y163975D01*
X424831Y164042D01*
X424364Y163909D01*
X423898Y163509D01*
G01X415831Y160042D02*
Y164042D01*
G01X416764Y161375D02*
X414898D01*
G01X411231Y164042D02*
X411631Y163975D01*
X412031Y163709D01*
X412298Y163242D01*
X412431Y162709D01*
X412298Y162175D01*
X412031Y161709D01*
X411631Y161442D01*
X411231Y161375D01*
X410831Y161442D01*
X410431Y161709D01*
X410164Y162175D01*
X410098Y162709D01*
X410164Y163242D01*
X410431Y163709D01*
X410831Y163975D01*
X411231Y164042D01*
G01X406631D02*
Y160042D01*
G01X403031Y162242D02*
X400898D01*
X401098Y161775D01*
X401431Y161509D01*
X401898Y161375D01*
X402364Y161442D01*
X402764Y161642D01*
X403031Y162109D01*
X403164Y162509D01*
Y162909D01*
X403031Y163309D01*
X402698Y163709D01*
X402298Y163975D01*
X401831Y164042D01*
X401364Y163909D01*
X400898Y163509D01*
G01X398364Y164042D02*
Y161375D01*
G01Y161909D02*
X398031Y161642D01*
X397698Y161442D01*
X397231Y161375D01*
X396898Y161442D01*
X396498Y161642D01*
G01X391631Y164042D02*
Y161375D01*
G01Y161842D02*
X391898Y161575D01*
X392298Y161442D01*
X392764Y161375D01*
X393231Y161509D01*
X393631Y161775D01*
X393898Y162175D01*
X394031Y162709D01*
X393898Y163242D01*
X393631Y163642D01*
X393231Y163909D01*
X392764Y164042D01*
X392298Y163975D01*
X391898Y163775D01*
X391631Y163509D01*
G01X389364Y164042D02*
Y161375D01*
G01Y162042D02*
X389098Y161709D01*
X388698Y161442D01*
X388164Y161375D01*
X387698Y161442D01*
X387298Y161709D01*
X387098Y162175D01*
Y164042D01*
G01X382564Y161709D02*
X383031Y161442D01*
X383431Y161375D01*
X383964Y161509D01*
X384364Y161775D01*
X384631Y162242D01*
X384698Y162709D01*
X384631Y163175D01*
X384364Y163575D01*
X383964Y163909D01*
X383431Y164042D01*
X382964Y163909D01*
X382564Y163642D01*
G01X380031Y162242D02*
X377898D01*
X378098Y161775D01*
X378431Y161509D01*
X378898Y161375D01*
X379364Y161442D01*
X379764Y161642D01*
X380031Y162109D01*
X380164Y162509D01*
Y162909D01*
X380031Y163309D01*
X379698Y163709D01*
X379298Y163975D01*
X378831Y164042D01*
X378364Y163909D01*
X377898Y163509D01*
G01X370564Y162709D02*
X368964D01*
G01X369831Y161842D02*
Y163575D01*
G01X366431Y164175D02*
X364031Y160042D01*
G01X361498Y162709D02*
X359764D01*
G01X357298Y160709D02*
X356898Y160309D01*
X356431Y160109D01*
X355898Y160042D01*
X355231Y160175D01*
X354764Y160509D01*
X354631Y160909D01*
X354698Y161309D01*
X354964Y161642D01*
X356298Y162309D01*
X356898Y162775D01*
X357298Y163442D01*
X357431Y164042D01*
X354631D01*
G01X348831D02*
Y161375D01*
G01Y162109D02*
X348631Y161775D01*
X348298Y161509D01*
X347831Y161375D01*
X347364Y161509D01*
X347031Y161775D01*
X346831Y162109D01*
Y164042D01*
G01Y162109D02*
X346631Y161775D01*
X346298Y161509D01*
X345831Y161375D01*
X345364Y161509D01*
X345031Y161775D01*
X344831Y162175D01*
Y164042D01*
G01X342231Y161375D02*
Y164042D01*
G01Y160309D02*
X342364Y160242D01*
Y160109D01*
X342231Y160042D01*
X342098Y160109D01*
Y160242D01*
X342231Y160309D01*
G01X337631Y164042D02*
Y160042D01*
G01X334031Y163575D02*
X333698Y163842D01*
X333231Y164042D01*
X332831D01*
X332431Y163909D01*
X332164Y163709D01*
X332031Y163442D01*
X332098Y163042D01*
X332364Y162842D01*
X333564Y162442D01*
X333831Y161975D01*
X333698Y161642D01*
X333431Y161442D01*
X333031Y161375D01*
X332631Y161442D01*
X332231Y161642D01*
G01X550564Y229790D02*
Y225790D01*
X548964D01*
X548431Y225990D01*
X548031Y226457D01*
X547898Y226990D01*
X548031Y227523D01*
X548364Y227923D01*
X548964Y228123D01*
X550564D01*
G01X545564Y229790D02*
Y227123D01*
G01Y227657D02*
X545231Y227390D01*
X544898Y227190D01*
X544431Y227123D01*
X544098Y227190D01*
X543698Y227390D01*
G01X541031Y227990D02*
X538898D01*
X539098Y227523D01*
X539431Y227257D01*
X539898Y227123D01*
X540364Y227190D01*
X540764Y227390D01*
X541031Y227857D01*
X541164Y228257D01*
Y228657D01*
X541031Y229057D01*
X540698Y229457D01*
X540298Y229723D01*
X539831Y229790D01*
X539364Y229657D01*
X538898Y229257D01*
G01X536431Y229323D02*
X536098Y229590D01*
X535631Y229790D01*
X535231D01*
X534831Y229657D01*
X534564Y229457D01*
X534431Y229190D01*
X534498Y228790D01*
X534764Y228590D01*
X535964Y228190D01*
X536231Y227723D01*
X536098Y227390D01*
X535831Y227190D01*
X535431Y227123D01*
X535031Y227190D01*
X534631Y227390D01*
G01X531831Y229323D02*
X531498Y229590D01*
X531031Y229790D01*
X530631D01*
X530231Y229657D01*
X529964Y229457D01*
X529831Y229190D01*
X529898Y228790D01*
X530164Y228590D01*
X531364Y228190D01*
X531631Y227723D01*
X531498Y227390D01*
X531231Y227190D01*
X530831Y227123D01*
X530431Y227190D01*
X530031Y227390D01*
G01X527098Y228457D02*
X525364D01*
G01X522031Y229790D02*
Y226390D01*
X521898Y226057D01*
X521631Y225857D01*
X521231Y225790D01*
X520831Y225923D01*
X520631Y226257D01*
G01X521431Y227390D02*
X522764D01*
G01X517031Y227123D02*
Y229790D01*
G01Y226057D02*
X517164Y225990D01*
Y225857D01*
X517031Y225790D01*
X516898Y225857D01*
Y225990D01*
X517031Y226057D01*
G01X512431Y225790D02*
Y229790D01*
G01X513364Y227123D02*
X511498D01*
G01X504564Y229790D02*
Y225790D01*
X502964D01*
X502431Y225990D01*
X502031Y226457D01*
X501898Y226990D01*
X502031Y227523D01*
X502364Y227923D01*
X502964Y228123D01*
X504564D01*
G01X498631Y225790D02*
Y229790D01*
G01X500164Y225790D02*
X497098D01*
G01X495431Y229790D02*
Y225790D01*
G01X492631D02*
Y229790D01*
G01Y227790D02*
X495431D01*
G01X485964Y229790D02*
Y225790D01*
G01X483831Y227123D02*
X485964Y228657D01*
G01X485098Y228057D02*
X483698Y229790D01*
G01X481231Y227990D02*
X479098D01*
X479298Y227523D01*
X479631Y227257D01*
X480098Y227123D01*
X480564Y227190D01*
X480964Y227390D01*
X481231Y227857D01*
X481364Y228257D01*
Y228657D01*
X481231Y229057D01*
X480898Y229457D01*
X480498Y229723D01*
X480031Y229790D01*
X479564Y229657D01*
X479098Y229257D01*
G01X476631Y227990D02*
X474498D01*
X474698Y227523D01*
X475031Y227257D01*
X475498Y227123D01*
X475964Y227190D01*
X476364Y227390D01*
X476631Y227857D01*
X476764Y228257D01*
Y228657D01*
X476631Y229057D01*
X476298Y229457D01*
X475898Y229723D01*
X475431Y229790D01*
X474964Y229657D01*
X474498Y229257D01*
G01X472231Y231123D02*
Y227123D01*
G01Y227723D02*
X471898Y227390D01*
X471564Y227190D01*
X471031Y227123D01*
X470564Y227190D01*
X470098Y227523D01*
X469898Y227990D01*
X469831Y228457D01*
X469898Y228923D01*
X470098Y229390D01*
X470498Y229657D01*
X471031Y229790D01*
X471498Y229723D01*
X471964Y229523D01*
X472231Y229257D01*
G01X462964Y229790D02*
Y225790D01*
G01Y227723D02*
X462631Y227390D01*
X462298Y227190D01*
X461764Y227123D01*
X461364Y227190D01*
X460898Y227457D01*
X460698Y227857D01*
Y229790D01*
G01X457231D02*
X457631Y229723D01*
X458031Y229457D01*
X458298Y228990D01*
X458431Y228457D01*
X458298Y227923D01*
X458031Y227457D01*
X457631Y227190D01*
X457231Y227123D01*
X456831Y227190D01*
X456431Y227457D01*
X456164Y227923D01*
X456098Y228457D01*
X456164Y228990D01*
X456431Y229457D01*
X456831Y229723D01*
X457231Y229790D01*
G01X452631D02*
Y225790D01*
G01X449031Y227990D02*
X446898D01*
X447098Y227523D01*
X447431Y227257D01*
X447898Y227123D01*
X448364Y227190D01*
X448764Y227390D01*
X449031Y227857D01*
X449164Y228257D01*
Y228657D01*
X449031Y229057D01*
X448698Y229457D01*
X448298Y229723D01*
X447831Y229790D01*
X447364Y229657D01*
X446898Y229257D01*
G01X439831Y229323D02*
X439498Y229590D01*
X439031Y229790D01*
X438631D01*
X438231Y229657D01*
X437964Y229457D01*
X437831Y229190D01*
X437898Y228790D01*
X438164Y228590D01*
X439364Y228190D01*
X439631Y227723D01*
X439498Y227390D01*
X439231Y227190D01*
X438831Y227123D01*
X438431Y227190D01*
X438031Y227390D01*
G01X434231Y227123D02*
Y229790D01*
G01Y226057D02*
X434364Y225990D01*
Y225857D01*
X434231Y225790D01*
X434098Y225857D01*
Y225990D01*
X434231Y226057D01*
G01X430631Y227123D02*
X428631D01*
X430631Y229790D01*
X428631D01*
G01X426031Y227990D02*
X423898D01*
X424098Y227523D01*
X424431Y227257D01*
X424898Y227123D01*
X425364Y227190D01*
X425764Y227390D01*
X426031Y227857D01*
X426164Y228257D01*
Y228657D01*
X426031Y229057D01*
X425698Y229457D01*
X425298Y229723D01*
X424831Y229790D01*
X424364Y229657D01*
X423898Y229257D01*
G01X415831Y225790D02*
Y229790D01*
G01X416764Y227123D02*
X414898D01*
G01X411231Y229790D02*
X411631Y229723D01*
X412031Y229457D01*
X412298Y228990D01*
X412431Y228457D01*
X412298Y227923D01*
X412031Y227457D01*
X411631Y227190D01*
X411231Y227123D01*
X410831Y227190D01*
X410431Y227457D01*
X410164Y227923D01*
X410098Y228457D01*
X410164Y228990D01*
X410431Y229457D01*
X410831Y229723D01*
X411231Y229790D01*
G01X406631D02*
Y225790D01*
G01X403031Y227990D02*
X400898D01*
X401098Y227523D01*
X401431Y227257D01*
X401898Y227123D01*
X402364Y227190D01*
X402764Y227390D01*
X403031Y227857D01*
X403164Y228257D01*
Y228657D01*
X403031Y229057D01*
X402698Y229457D01*
X402298Y229723D01*
X401831Y229790D01*
X401364Y229657D01*
X400898Y229257D01*
G01X398364Y229790D02*
Y227123D01*
G01Y227657D02*
X398031Y227390D01*
X397698Y227190D01*
X397231Y227123D01*
X396898Y227190D01*
X396498Y227390D01*
G01X391631Y229790D02*
Y227123D01*
G01Y227590D02*
X391898Y227323D01*
X392298Y227190D01*
X392764Y227123D01*
X393231Y227257D01*
X393631Y227523D01*
X393898Y227923D01*
X394031Y228457D01*
X393898Y228990D01*
X393631Y229390D01*
X393231Y229657D01*
X392764Y229790D01*
X392298Y229723D01*
X391898Y229523D01*
X391631Y229257D01*
G01X389364Y229790D02*
Y227123D01*
G01Y227790D02*
X389098Y227457D01*
X388698Y227190D01*
X388164Y227123D01*
X387698Y227190D01*
X387298Y227457D01*
X387098Y227923D01*
Y229790D01*
G01X382564Y227457D02*
X383031Y227190D01*
X383431Y227123D01*
X383964Y227257D01*
X384364Y227523D01*
X384631Y227990D01*
X384698Y228457D01*
X384631Y228923D01*
X384364Y229323D01*
X383964Y229657D01*
X383431Y229790D01*
X382964Y229657D01*
X382564Y229390D01*
G01X380031Y227990D02*
X377898D01*
X378098Y227523D01*
X378431Y227257D01*
X378898Y227123D01*
X379364Y227190D01*
X379764Y227390D01*
X380031Y227857D01*
X380164Y228257D01*
Y228657D01*
X380031Y229057D01*
X379698Y229457D01*
X379298Y229723D01*
X378831Y229790D01*
X378364Y229657D01*
X377898Y229257D01*
G01X370564Y228457D02*
X368964D01*
G01X369831Y227590D02*
Y229323D01*
G01X366431Y229923D02*
X364031Y225790D01*
G01X361498Y228457D02*
X359764D01*
G01X357298Y226457D02*
X356898Y226057D01*
X356431Y225857D01*
X355898Y225790D01*
X355231Y225923D01*
X354764Y226257D01*
X354631Y226657D01*
X354698Y227057D01*
X354964Y227390D01*
X356298Y228057D01*
X356898Y228523D01*
X357298Y229190D01*
X357431Y229790D01*
X354631D01*
G01X348831D02*
Y227123D01*
G01Y227857D02*
X348631Y227523D01*
X348298Y227257D01*
X347831Y227123D01*
X347364Y227257D01*
X347031Y227523D01*
X346831Y227857D01*
Y229790D01*
G01Y227857D02*
X346631Y227523D01*
X346298Y227257D01*
X345831Y227123D01*
X345364Y227257D01*
X345031Y227523D01*
X344831Y227923D01*
Y229790D01*
G01X342231Y227123D02*
Y229790D01*
G01Y226057D02*
X342364Y225990D01*
Y225857D01*
X342231Y225790D01*
X342098Y225857D01*
Y225990D01*
X342231Y226057D01*
G01X337631Y229790D02*
Y225790D01*
G01X334031Y229323D02*
X333698Y229590D01*
X333231Y229790D01*
X332831D01*
X332431Y229657D01*
X332164Y229457D01*
X332031Y229190D01*
X332098Y228790D01*
X332364Y228590D01*
X333564Y228190D01*
X333831Y227723D01*
X333698Y227390D01*
X333431Y227190D01*
X333031Y227123D01*
X332631Y227190D01*
X332231Y227390D01*
G01X342520Y264567D02*
G03X344488Y266536I0J1968D01*
G01X342520Y634252D02*
G03X344488Y636221I0J1968D01*
G01X359026Y148392D02*
X359029Y159492D01*
G01X357532Y153392D02*
X359026Y148392D01*
X360522Y153392D01*
X357532D01*
G01X364331Y137992D02*
X354331D01*
Y147992D01*
X364331D01*
Y137992D01*
G01X359026Y214140D02*
X359029Y225240D01*
G01X357532Y219140D02*
X359026Y214140D01*
X360522Y219140D01*
X357532D01*
G01X364331Y203740D02*
X354331D01*
Y213740D01*
X364331D01*
Y203740D01*
G01X346457Y270473D02*
G03X344488Y268504I0J-1969D01*
G01X346457Y270473D02*
X535433D01*
G01X344488Y268504D02*
Y266536D01*
G01X350394Y320473D02*
G03X348426Y318504I0J-1968D01*
G01Y316536D02*
G03X350394Y314567I1968J-1D01*
G01D02*
X456693D01*
G01Y320473D02*
X350394D01*
G01X348426Y318504D02*
Y316536D01*
G01X346457Y640158D02*
G03X344488Y638189I0J-1969D01*
G01X346457Y640158D02*
X535433D01*
G01X344488Y638189D02*
Y636221D01*
G01X350394Y690158D02*
G03X348426Y688189I0J-1968D01*
G01Y686221D02*
G03X350394Y684252I1968J-1D01*
G01D02*
X456693D01*
G01Y690158D02*
X350394D01*
G01X348426Y688189D02*
Y686221D01*
G01X383859Y1969D02*
G03X385827Y0I1968J-1D01*
G01D02*
X523622D01*
G01X372048D02*
G03X375985Y3937I0J3937D01*
G01X383859Y1969D02*
Y32677D01*
G01X375985Y3937D02*
Y94488D01*
G01X383859Y32677D02*
G03X375985I-3937J0D01*
G01Y57874D02*
G03X383859I3937J0D01*
G01D02*
Y90551D01*
G01X379922Y98425D02*
G03X375985Y94488I0J-3937D01*
G01X458071Y90551D02*
X383859D01*
G01X462008Y98425D02*
X379922D01*
G01X412931Y134292D02*
Y141192D01*
X375431D01*
Y134292D01*
X412931D01*
G01X375985Y166334D02*
G03X377953Y164365I1969J0D01*
G01X375985Y180113D02*
Y166334D01*
G01X377953Y164365D02*
X484252D01*
G01X377953Y182082D02*
G03X375985Y180113I0J-1968D01*
G01X484252Y182082D02*
X377953D01*
G01X412931Y200040D02*
Y206940D01*
X375431D01*
Y200040D01*
X412931D01*
G01X383859Y369685D02*
X465355D01*
G01X372048D02*
G03X375985Y373622I0J3937D01*
G01X383859Y369685D02*
Y402362D01*
G01X375985Y373622D02*
Y464173D01*
G01X383859Y402362D02*
G03X375985I-3937J0D01*
G01Y427559D02*
G03X383859I3937J0D01*
G01D02*
Y460236D01*
G01X379922Y468110D02*
G03X375985Y464173I0J-3937D01*
G01X458071Y460236D02*
X383859D01*
G01X462008Y468110D02*
X379922D01*
G01X375985Y536019D02*
G03X377953Y534050I1969J0D01*
G01D02*
X484252D01*
G01X377953Y551767D02*
G03X375985Y549799I0J-1968D01*
G01D02*
Y536019D01*
G01X484252Y551767D02*
X377953D01*
G01X395077Y141192D02*
X395031Y161592D01*
G01X393571Y146189D02*
X395077Y141192D01*
X396561Y146195D01*
X393571Y146189D01*
G01X433731Y148592D02*
Y154292D01*
X409731D01*
Y148592D01*
X433731D01*
G01X395077Y206940D02*
X395031Y227340D01*
G01X393571Y211937D02*
X395077Y206940D01*
X396561Y211943D01*
X393571Y211937D01*
G01X433731Y214340D02*
Y220040D01*
X409731D01*
Y214340D01*
X433731D01*
G01X508231Y133992D02*
Y141392D01*
X430831D01*
Y133892D01*
X508131D01*
G01X422901Y154292D02*
X422931Y161692D01*
G01X421426Y159298D02*
X422901Y154292D01*
X424416Y159286D01*
X421426Y159298D01*
G01X508231Y199740D02*
Y207140D01*
X430831D01*
Y199640D01*
X508131D01*
G01X422901Y220040D02*
X422931Y227440D01*
G01X421426Y225046D02*
X422901Y220040D01*
X424416Y225034D01*
X421426Y225046D01*
G01X429922Y260630D02*
Y266536D01*
G01X425985Y256693D02*
G03X429922Y260630I0J3937D01*
G01Y266536D02*
G03X425985Y270473I-3937J0D01*
G01X429922Y630315D02*
Y636221D01*
G01X425985Y626378D02*
G03X429922Y630315I0J3937D01*
G01Y636221D02*
G03X425985Y640158I-3937J0D01*
G01X455026Y141392D02*
X455031Y159892D01*
G01X453532Y146392D02*
X455026Y141392D01*
X456522Y146392D01*
X453532D01*
G01X455026Y207140D02*
X455031Y225640D01*
G01X453532Y212140D02*
X455026Y207140D01*
X456522Y212140D01*
X453532D01*
G01X452756Y260630D02*
G03X456693Y256693I3937J0D01*
G01X452756Y260630D02*
Y266536D01*
G01X456693Y270473D02*
G03X452756Y266536I0J-3937D01*
G01X458662Y318504D02*
G03X456693Y320473I-1969J0D01*
G01Y314567D02*
G03X458662Y316536I0J1969D01*
G01X452756Y630315D02*
G03X456693Y626378I3937J0D01*
G01X452756Y630315D02*
Y636221D01*
G01X456693Y640158D02*
G03X452756Y636221I0J-3937D01*
G01X458662Y688189D02*
G03X456693Y690158I-1969J0D01*
G01Y684252D02*
G03X458662Y686221I0J1969D01*
G01X458071Y78937D02*
G03X469882Y67126I11811J0D01*
G01X465945Y78937D02*
G03X469882Y75000I3937J0D01*
G01X458071Y90551D02*
Y78937D01*
G01X465945Y94488D02*
Y78937D01*
G01X469882Y67126D02*
X525591D01*
G01X469882Y75000D02*
X529528D01*
G01X465945Y94488D02*
G03X462008Y98425I-3937J0D01*
G01X458662Y316536D02*
Y318504D01*
G01X465355Y361811D02*
G03Y369685I0J3937D01*
G01X458071Y448622D02*
G03X469882Y436811I11811J0D01*
G01D02*
X525591D01*
G01X465945Y448622D02*
G03X469882Y444685I3937J0D01*
G01X465945Y464173D02*
G03X462008Y468110I-3937J0D01*
G01X458071Y460236D02*
Y448622D01*
G01X465945Y464173D02*
Y448622D01*
G01X469882Y444685D02*
X529528D01*
G01X458662Y686221D02*
Y688189D01*
G01X484252Y164365D02*
G03X486221Y166334I0J1969D01*
G01D02*
Y180113D01*
G01D02*
G03X484252Y182082I-1969J0D01*
G01X496063Y369685D02*
G03Y361811I0J-3937D01*
G01Y369685D02*
X525591D01*
G01X484252Y534050D02*
G03X486221Y536019I0J1969D01*
G01Y549799D02*
G03X484252Y551767I-1969J-1D01*
G01X486221Y536019D02*
Y549799D01*
G01X523622Y0D02*
G03X525591Y1969I0J1969D01*
G01X524526Y147892D02*
X524529Y159492D01*
G01X523032Y152892D02*
X524526Y147892D01*
X526022Y152892D01*
X523032D01*
G01X519831Y137992D02*
X529331D01*
Y147492D01*
X519831D01*
Y137992D01*
G01X524526Y213640D02*
X524529Y225240D01*
G01X523032Y218640D02*
X524526Y213640D01*
X526022Y218640D01*
X523032D01*
G01X519831Y203740D02*
X529331D01*
Y213240D01*
X519831D01*
Y203740D01*
G01X533465Y3937D02*
G03X537402Y0I3937J0D01*
G01X525591Y1969D02*
Y20965D01*
G01X533465Y3937D02*
Y71063D01*
G01X537402Y0D02*
X561024D01*
G01X533465Y20965D02*
G03X525591I-3937J0D01*
G01Y46162D02*
G03X533465I3937J0D01*
G01X525591D02*
Y67126D01*
G01X533465Y71063D02*
G03X529528Y75000I-3937J0D01*
G01X535433Y270473D02*
G03X539370Y274410I0J3937D01*
G01D02*
Y357874D01*
G01X547244Y270473D02*
X562992D01*
G01X547244D02*
Y303543D01*
G01D02*
G03X539370I-3937J0D01*
G01Y328740D02*
G03X547244I3937J0D01*
G01D02*
Y361811D01*
G01X539370Y357874D02*
G03X535433Y361811I-3937J0D01*
G01X547244D02*
X562992D01*
G01X533465Y373622D02*
G03X537402Y369685I3937J0D01*
G01X525591D02*
Y390650D01*
G01X533465Y373622D02*
Y440748D01*
G01X537402Y369685D02*
X561024D01*
G01X533465Y390650D02*
G03X525591I-3937J0D01*
G01Y415847D02*
G03X533465I3937J0D01*
G01X525591D02*
Y436811D01*
G01X533465Y440748D02*
G03X529528Y444685I-3937J0D01*
G01X535433Y640158D02*
G03X539370Y644095I0J3937D01*
G01D02*
Y727559D01*
G01X547244Y640158D02*
X562992D01*
G01X547244D02*
Y673228D01*
G01D02*
G03X539370I-3937J0D01*
G01Y698425D02*
G03X547244I3937J0D01*
G01D02*
Y727559D01*
G01X551181Y731496D02*
G03X547244Y727559I0J-3937D01*
G01X539370D02*
G03X535433Y731496I-3937J0D01*
G01X561024Y0D02*
G03X564961Y3937I0J3937D01*
G01D02*
Y252756D01*
G01D02*
G03X561024Y256693I-3937J0D01*
G01X562992Y270473D02*
G03X564961Y272441I1J1968D01*
G01D02*
Y359843D01*
G01D02*
G03X562992Y361811I-1968J0D01*
G01X561024Y369685D02*
G03X564961Y373622I0J3937D01*
G01D02*
Y622441D01*
G01D02*
G03X561024Y626378I-3937J0D01*
G01X562992Y640158D02*
G03X564961Y642126I1J1968D01*
G01D02*
Y721654D01*
G01D02*
G03X555118Y731496I-9842J0D01*
G01X551181D02*
X555118D01*
G54D15*
X60928Y64173D03*
X73567Y4087D03*
X75100Y36700D03*
X74635Y29153D03*
X76804Y61699D03*
X76600Y68000D03*
X208000Y90000D03*
X204500D03*
X220310Y4087D03*
X222206Y41500D03*
X218600Y37400D03*
X217880Y83600D03*
X213100Y83500D03*
X268045Y8270D03*
X258088Y21787D03*
X273551Y37112D03*
X293146Y81023D03*
X293141Y97997D03*
X279500Y116900D03*
X279437Y120731D03*
X322100Y26600D03*
X303900Y28900D03*
X313900Y27200D03*
X315166Y52172D03*
X313617Y81023D03*
X321440Y101571D03*
X308208Y101945D03*
X303734Y89882D03*
X309250Y127439D03*
X322042Y147196D03*
X310500Y184328D03*
X340000Y14667D03*
X324700Y16300D03*
X329962Y56703D03*
X337406Y79575D03*
X341133Y80298D03*
X326892Y79371D03*
X338145Y98740D03*
X337670Y90976D03*
X332822Y103140D03*
X327057Y90943D03*
X343028Y87447D03*
X327114Y87334D03*
X340874Y96311D03*
X325404Y101215D03*
X343028Y83447D03*
X327114Y83334D03*
X340874Y92311D03*
X329404Y101215D03*
X336238Y148951D03*
X351040Y34753D03*
X358900Y23928D03*
X345642Y90134D03*
X506868Y166599D03*
X658381Y653446D03*
G54D16*
X93287Y10039D03*
X88287D03*
X93287Y54528D03*
X88287D03*
X118287Y10039D03*
X113287D03*
X108287D03*
X103287D03*
X98287D03*
X118287Y54528D03*
X113287D03*
X108287D03*
X103287D03*
X98287D03*
X163287Y10039D03*
X158287D03*
X153287D03*
X148287D03*
X143287D03*
X163287Y54528D03*
X158287D03*
X153287D03*
X148287D03*
X143287D03*
X183287Y10039D03*
X178287D03*
X173287D03*
X168287D03*
X183287Y54528D03*
X178287D03*
X173287D03*
X168287D03*
X208287Y10039D03*
X203287D03*
X198287D03*
X193287D03*
X188287D03*
X208287Y54528D03*
X203287D03*
X198287D03*
X193287D03*
X188287D03*
X213287Y10039D03*
Y54528D03*
X389331Y137992D03*
X384331D03*
X379331D03*
X389331Y203740D03*
X384331D03*
X379331D03*
X409331Y137992D03*
X404331D03*
X399331D03*
X394331D03*
X409331Y203740D03*
X404331D03*
X399331D03*
X394331D03*
X434331Y137992D03*
Y203740D03*
X459331Y137992D03*
X454331D03*
X449331D03*
X444331D03*
X439331D03*
X459331Y203740D03*
X454331D03*
X449331D03*
X444331D03*
X439331D03*
X479331Y137992D03*
X474331D03*
X469331D03*
X464331D03*
X479331Y203740D03*
X474331D03*
X469331D03*
X464331D03*
X504331Y137992D03*
X499331D03*
X494331D03*
X489331D03*
X484331D03*
X504331Y203740D03*
X499331D03*
X494331D03*
X489331D03*
X484331D03*
X658381Y578446D03*
G54D17*
X140237Y23464D03*
X137087D03*
X133937D03*
X130787D03*
X127637D03*
X124487D03*
X121337D03*
X140237Y67953D03*
X137087D03*
X133937D03*
X130787D03*
X127637D03*
X124487D03*
X121337D03*
X412381Y151417D03*
Y217165D03*
X431281Y151417D03*
X428131D03*
X424981D03*
X421831D03*
X418681D03*
X415531D03*
X431281Y217165D03*
X428131D03*
X424981D03*
X421831D03*
X418681D03*
X415531D03*
X658381Y603446D03*
G54D18*
X225097Y15039D03*
Y59528D03*
X516141Y142992D03*
Y208740D03*
X658381Y403446D03*
G54D19*
X295472Y65571D03*
Y108287D03*
X330590Y65571D03*
Y108287D03*
X658381Y353446D03*
M02*
